# Altium SchDoc records: 02-USER_IO_STATUS.SchDoc
|HEADER=Protel for Windows - Schematic Capture Binary File Version 5.0|Weight=1174|MinorVersion=7
|RECORD=31|FontIdCount=17|Size1=10|FontName1=Times New Roman|Size2=10|Rotation2=90|FontName2=Times New Roman|Size3=10|Underline3=T|FontName3=Times New Roman|Size4=8|FontName4=Arial|Size5=10|FontName5=Arial|Size6=24|FontName6=Times New Roman|Size7=12|FontName7=Arial|Size8=14|FontName8=Times New Roman|Size9=14|FontName9=Arial|Size10=9|FontName10=Arial|Size11=9|FontName11=Arial Narrow|Size12=22|FontName12=Arial Narrow|Size13=14|FontName13=Arial Narrow|Size14=6|Rotation14=90|FontName14=Arial|Size15=6|FontName15=Arial|Size16=24|FontName16=Arial|Size17=9|Rotation17=90|FontName17=Arial|UseMBCS=T|IsBOC=T|HotSpotGridOn=T|HotSpotGridSize=2|SheetStyle=6|SystemFont=5|TitleBlockOn=T|SheetNumberSpaceSize=12|AreaColor=16317695|SnapGridOn=T|SnapGridSize=5|VisibleGridOn=T|VisibleGridSize=10|CustomX=1700|CustomY=1100|CustomXZones=8|CustomYZones=6|CustomMarginWidth=20|Display_Unit=0|ReferenceZoneStyle=1
|RECORD=39|IsNotAccesible=T|OwnerPartId=-1|FileName=C:\Users\<user>\Documents\Altium\AD21\Templates\ANSI B Landscape.SchDot
|RECORD=4|OwnerIndex=1|OwnerPartId=-1|Location.X=1345|Location.Y=1068|FontID=11|Text=REVISION
|RECORD=4|OwnerIndex=1|IndexInSheet=1|OwnerPartId=-1|Location.X=1460|Location.Y=1068|FontID=11|Text=DESCRIPTION
|RECORD=4|OwnerIndex=1|IndexInSheet=2|OwnerPartId=-1|Location.X=1592|Location.Y=1068|FontID=11|Text=DATE
|RECORD=4|OwnerIndex=1|IndexInSheet=3|OwnerPartId=-1|Location.X=1633|Location.Y=1068|FontID=11|Text=APPROVED
|RECORD=6|OwnerIndex=1|IndexInSheet=4|OwnerPartId=-1|LocationCount=3|X1=1340|Y1=1080|X2=1340|Y2=1065|X3=1680|Y3=1065
|RECORD=6|OwnerIndex=1|IndexInSheet=5|OwnerPartId=-1|LocationCount=2|X1=1380|Y1=1080|X2=1380|Y2=1065
|RECORD=6|OwnerIndex=1|IndexInSheet=6|OwnerPartId=-1|LocationCount=2|X1=1620|Y1=1080|X2=1620|Y2=1065
|RECORD=6|OwnerIndex=1|IndexInSheet=7|OwnerPartId=-1|LocationCount=2|X1=1580|Y1=1080|X2=1580|Y2=1065
|RECORD=6|OwnerIndex=1|IndexInSheet=8|OwnerPartId=-1|LocationCount=3|X1=1340|Y1=1070|X2=1340|Y2=1050|X3=1680|Y3=1050
|RECORD=6|OwnerIndex=1|IndexInSheet=9|OwnerPartId=-1|LocationCount=2|X1=1380|Y1=1065|X2=1380|Y2=1050
|RECORD=6|OwnerIndex=1|IndexInSheet=10|OwnerPartId=-1|LocationCount=2|X1=1580|Y1=1065|X2=1580|Y2=1050
|RECORD=6|OwnerIndex=1|IndexInSheet=11|OwnerPartId=-1|LocationCount=2|X1=1620|Y1=1065|X2=1620|Y2=1050
|RECORD=6|OwnerIndex=1|IndexInSheet=12|OwnerPartId=-1|LineWidth=1|LocationCount=2|X1=1695|Y1=184|X2=1700|Y2=184
|RECORD=4|OwnerIndex=1|IndexInSheet=13|OwnerPartId=-1|Location.X=1689|Location.Y=189|Orientation=3|FontID=14|Text=REV.
|RECORD=4|OwnerIndex=1|IndexInSheet=14|OwnerPartId=-1|Location.X=1689|Location.Y=174|Orientation=3|FontID=14|Text=SHT.
|RECORD=4|OwnerIndex=1|IndexInSheet=15|OwnerPartId=-1|Location.X=1695|Location.Y=259|Orientation=3|Justification=6|FontID=14|Text=DWG. NO.|IsMirrored=T
|RECORD=4|OwnerIndex=1|IndexInSheet=16|OwnerPartId=-1|Location.X=1680|Location.Y=258|Orientation=3|FontID=17|Text==DOC_NO_SCH_DWG
|RECORD=4|OwnerIndex=1|IndexInSheet=17|OwnerPartId=-1|Location.X=1680|Location.Y=182|Orientation=3|Justification=1|FontID=17|Text==ItemRevision
|RECORD=4|OwnerIndex=1|IndexInSheet=18|OwnerPartId=-1|Location.X=1680|Location.Y=169|Orientation=3|Justification=1|FontID=17|Text==SheetNumber
|RECORD=6|OwnerIndex=1|IndexInSheet=19|OwnerPartId=-1|LineWidth=1|LocationCount=3|X1=1695|Y1=160|X2=1695|Y2=260|X3=1680|Y3=260
|RECORD=6|OwnerIndex=1|IndexInSheet=20|OwnerPartId=-1|LocationCount=2|X1=1695|Y1=175|X2=1680|Y2=175
|RECORD=6|OwnerIndex=1|IndexInSheet=21|OwnerPartId=-1|LocationCount=2|X1=1695|Y1=190|X2=1680|Y2=190
|RECORD=6|OwnerIndex=1|IndexInSheet=22|OwnerPartId=-1|LineWidth=1|LocationCount=2|X1=1695|Y1=160|X2=1680|Y2=160
|RECORD=4|OwnerIndex=1|IndexInSheet=23|OwnerPartId=-1|Location.X=1312|Location.Y=1080|FontID=15|Text=REV.
|RECORD=4|OwnerIndex=1|IndexInSheet=24|OwnerPartId=-1|Location.X=1327|Location.Y=1080|FontID=15|Text=SHT.
|RECORD=4|OwnerIndex=1|IndexInSheet=25|OwnerPartId=-1|Location.X=1283|Location.Y=1086|Justification=6|FontID=15|Text=DWG. NO.|IsMirrored=T
|RECORD=4|OwnerIndex=1|IndexInSheet=26|OwnerPartId=-1|Location.X=1247|Location.Y=1085|FontID=10|Text==DOC_NO_SCH_DWG
|RECORD=4|OwnerIndex=1|IndexInSheet=27|OwnerPartId=-1|Location.X=1317|Location.Y=1085|Justification=1|FontID=10|Text==ItemRevision
|RECORD=4|OwnerIndex=1|IndexInSheet=28|OwnerPartId=-1|Location.X=1332|Location.Y=1085|Justification=1|FontID=10|Text==SheetNumber
|RECORD=6|OwnerIndex=1|IndexInSheet=29|OwnerPartId=-1|LineWidth=1|LocationCount=3|X1=1340|Y1=1095|X2=1240|Y2=1095|X3=1240|Y3=1080
|RECORD=6|OwnerIndex=1|IndexInSheet=30|OwnerPartId=-1|LocationCount=2|X1=1325|Y1=1095|X2=1325|Y2=1080
|RECORD=6|OwnerIndex=1|IndexInSheet=31|OwnerPartId=-1|LocationCount=2|X1=1310|Y1=1095|X2=1310|Y2=1080
|RECORD=6|OwnerIndex=1|IndexInSheet=32|OwnerPartId=-1|LineWidth=1|LocationCount=2|X1=1340|Y1=1095|X2=1340|Y2=1080
|RECORD=7|OwnerIndex=1|IndexInSheet=33|OwnerPartId=-1|IsSolid=T|LocationCount=3|X1=850|Y1=1080|X2=855|Y2=1090|X3=845|Y3=1090
|RECORD=7|OwnerIndex=1|IndexInSheet=34|OwnerPartId=-1|IsSolid=T|LocationCount=3|X1=850|Y1=20|X2=845|Y2=10|X3=855|Y3=10
|RECORD=7|OwnerIndex=1|IndexInSheet=35|OwnerPartId=-1|IsSolid=T|LocationCount=3|X1=1680|Y1=550|X2=1690|Y2=545|X3=1690|Y3=555
|RECORD=28|OwnerIndex=1|IndexInSheet=36|OwnerPartId=-1|UnionIndex=1|Location.X=25|Location.Y=1033|Corner.X=298|Corner.Y=1075|AreaColor=16777215|FontID=5|Alignment=1|WordWrap=T|Text=THIS DOCUMENT AND THE DATA DISCLOSED HEREIN OR HEREWITH IS THE PROPERTY OF ALTIUM LIMITED AND MAY BE FREELY DISTRIBUTED IN WHOLE. NO RIGHTS ARE RESERVED OR EXPRESS OR IMPLIED WARANTEE GIVEN.|TextMargin_Frac=5
|RECORD=6|OwnerIndex=1|IndexInSheet=37|OwnerPartId=-1|UnionIndex=1|LineWidth=1|LocationCount=5|X1=300|Y1=1080|X2=20|Y2=1080|X3=20|Y3=1032|X4=300|Y4=1032|X5=300|Y5=1080
|RECORD=13|OwnerIndex=1|IndexInSheet=38|OwnerPartId=-1|Location.Y=1100|Corner.X=1699|Corner.X_Frac=83312|Corner.Y=1100|LineWidth=1
|RECORD=13|OwnerIndex=1|IndexInSheet=39|OwnerPartId=-1|Location.X=1699|Location.X_Frac=83312|Location.Y=1100|Corner.X=1699|Corner.X_Frac=83312|Corner.Y_Frac=16696|LineWidth=1
|RECORD=13|OwnerIndex=1|IndexInSheet=40|OwnerPartId=-1|Location.X=1699|Location.X_Frac=83312|Location.Y_Frac=16696|Corner.Y_Frac=16696|LineWidth=1
|RECORD=13|OwnerIndex=1|IndexInSheet=41|OwnerPartId=-1|Location.Y_Frac=16696|Corner.Y=1100|LineWidth=1
|RECORD=13|OwnerIndex=1|IndexInSheet=42|OwnerPartId=-1|Location.X=20|Location.X_Frac=12|Location.Y=1079|Location.Y_Frac=99791|Corner.X=1679|Corner.X_Frac=83296|Corner.Y=1079|Corner.Y_Frac=99791|LineWidth=1
|RECORD=13|OwnerIndex=1|IndexInSheet=43|OwnerPartId=-1|Location.X=1679|Location.X_Frac=83296|Location.Y=1079|Location.Y_Frac=99791|Corner.X=1679|Corner.X_Frac=83296|Corner.Y=20|Corner.Y_Frac=16904|LineWidth=1
|RECORD=13|OwnerIndex=1|IndexInSheet=44|OwnerPartId=-1|Location.X=1679|Location.X_Frac=83296|Location.Y=20|Location.Y_Frac=16904|Corner.X=20|Corner.X_Frac=12|Corner.Y=20|Corner.Y_Frac=16904|LineWidth=1
|RECORD=13|OwnerIndex=1|IndexInSheet=45|OwnerPartId=-1|Location.X=20|Location.X_Frac=12|Location.Y=20|Location.Y_Frac=16904|Corner.X=20|Corner.X_Frac=12|Corner.Y=1079|Corner.Y_Frac=99791|LineWidth=1
|RECORD=13|OwnerIndex=1|IndexInSheet=46|OwnerPartId=-1|Location.X=1487|Location.X_Frac=50000|Location.Y=20|Corner.X=1487|Corner.X_Frac=50000|LineWidth=1
|RECORD=13|OwnerIndex=1|IndexInSheet=47|OwnerPartId=-1|Location.X=1487|Location.X_Frac=50000|Location.Y=1080|Corner.X=1487|Corner.X_Frac=50000|Corner.Y=1100|LineWidth=1
|RECORD=13|OwnerIndex=1|IndexInSheet=48|OwnerPartId=-1|Location.X=1275|Location.Y=20|Corner.X=1275|LineWidth=1
|RECORD=13|OwnerIndex=1|IndexInSheet=49|OwnerPartId=-1|Location.X=1275|Location.Y=1095|Corner.X=1275|Corner.Y=1100|LineWidth=1
|RECORD=13|OwnerIndex=1|IndexInSheet=50|OwnerPartId=-1|Location.X=1062|Location.X_Frac=50000|Location.Y=20|Corner.X=1062|Corner.X_Frac=50000|LineWidth=1
|RECORD=13|OwnerIndex=1|IndexInSheet=51|OwnerPartId=-1|Location.X=1062|Location.X_Frac=50000|Location.Y=1080|Corner.X=1062|Corner.X_Frac=50000|Corner.Y=1100|LineWidth=1
|RECORD=13|OwnerIndex=1|IndexInSheet=52|OwnerPartId=-1|Location.X=850|Location.Y=20|Corner.X=850|LineWidth=1
|RECORD=13|OwnerIndex=1|IndexInSheet=53|OwnerPartId=-1|Location.X=850|Location.Y=1080|Corner.X=850|Corner.Y=1100|LineWidth=1
|RECORD=13|OwnerIndex=1|IndexInSheet=54|OwnerPartId=-1|Location.X=637|Location.X_Frac=50000|Location.Y=20|Corner.X=637|Corner.X_Frac=50000|LineWidth=1
|RECORD=13|OwnerIndex=1|IndexInSheet=55|OwnerPartId=-1|Location.X=637|Location.X_Frac=50000|Location.Y=1080|Corner.X=637|Corner.X_Frac=50000|Corner.Y=1100|LineWidth=1
|RECORD=13|OwnerIndex=1|IndexInSheet=56|OwnerPartId=-1|Location.X=425|Location.Y=20|Corner.X=425|LineWidth=1
|RECORD=13|OwnerIndex=1|IndexInSheet=57|OwnerPartId=-1|Location.X=425|Location.Y=1080|Corner.X=425|Corner.Y=1100|LineWidth=1
|RECORD=13|OwnerIndex=1|IndexInSheet=58|OwnerPartId=-1|Location.X=212|Location.X_Frac=50000|Location.Y=20|Corner.X=212|Corner.X_Frac=50000|LineWidth=1
|RECORD=13|OwnerIndex=1|IndexInSheet=59|OwnerPartId=-1|Location.X=212|Location.X_Frac=50000|Location.Y=1080|Corner.X=212|Corner.X_Frac=50000|Corner.Y=1100|LineWidth=1
|RECORD=13|OwnerIndex=1|IndexInSheet=60|OwnerPartId=-1|Location.X=20|Location.Y=916|Location.Y_Frac=66664|Corner.Y=916|Corner.Y_Frac=66664|LineWidth=1
|RECORD=13|OwnerIndex=1|IndexInSheet=61|OwnerPartId=-1|Location.X=1680|Location.Y=916|Location.Y_Frac=66664|Corner.X=1700|Corner.Y=916|Corner.Y_Frac=66664|LineWidth=1
|RECORD=13|OwnerIndex=1|IndexInSheet=62|OwnerPartId=-1|Location.X=20|Location.Y=733|Location.Y_Frac=33328|Corner.Y=733|Corner.Y_Frac=33328|LineWidth=1
|RECORD=13|OwnerIndex=1|IndexInSheet=63|OwnerPartId=-1|Location.X=1680|Location.Y=733|Location.Y_Frac=33328|Corner.X=1700|Corner.Y=733|Corner.Y_Frac=33328|LineWidth=1
|RECORD=13|OwnerIndex=1|IndexInSheet=64|OwnerPartId=-1|Location.X=20|Location.Y=550|Corner.Y=550|LineWidth=1
|RECORD=13|OwnerIndex=1|IndexInSheet=65|OwnerPartId=-1|Location.X=1680|Location.Y=550|Corner.X=1700|Corner.Y=550|LineWidth=1
|RECORD=13|OwnerIndex=1|IndexInSheet=66|OwnerPartId=-1|Location.X=20|Location.Y=366|Location.Y_Frac=66664|Corner.Y=366|Corner.Y_Frac=66664|LineWidth=1
|RECORD=13|OwnerIndex=1|IndexInSheet=67|OwnerPartId=-1|Location.X=1680|Location.Y=366|Location.Y_Frac=66664|Corner.X=1700|Corner.Y=366|Corner.Y_Frac=66664|LineWidth=1
|RECORD=13|OwnerIndex=1|IndexInSheet=68|OwnerPartId=-1|Location.X=20|Location.Y=183|Location.Y_Frac=33330|Corner.Y=183|Corner.Y_Frac=33330|LineWidth=1
|RECORD=7|OwnerIndex=1|IndexInSheet=69|OwnerPartId=-1|IsSolid=T|LocationCount=3|X1=20|Y1=550|X2=10|Y2=545|X3=10|Y3=555
|RECORD=4|OwnerIndex=1|IndexInSheet=70|OwnerPartId=-1|Location.X=1348|Location.Y=71|FontID=16|Text==title
|RECORD=4|OwnerIndex=1|IndexInSheet=71|OwnerPartId=-1|Location.X=1450|Location.Y=40|FontID=13|Text==DOC_NO_SCH_DWG
|RECORD=6|OwnerIndex=1|IndexInSheet=72|OwnerPartId=-1|LocationCount=2|X1=1405|Y1=65|X2=1405|Y2=35
|RECORD=6|OwnerIndex=1|IndexInSheet=73|OwnerPartId=-1|LocationCount=2|X1=1680|Y1=35|X2=1320|Y2=35
|RECORD=6|OwnerIndex=1|IndexInSheet=74|OwnerPartId=-1|LocationCount=2|X1=1650|Y1=65|X2=1650|Y2=35
|RECORD=4|OwnerIndex=1|IndexInSheet=75|OwnerPartId=-1|Location.X=1330|Location.Y=35|FontID=12|Text=B
|RECORD=4|OwnerIndex=1|IndexInSheet=76|OwnerPartId=-1|Location.X=1428|Location.Y=20|FontID=7|Text==DocumentName
|RECORD=4|OwnerIndex=1|IndexInSheet=77|OwnerPartId=-1|Location.X=1615|Location.Y=20|FontID=7|Text==SheetNumber
|RECORD=4|OwnerIndex=1|IndexInSheet=78|OwnerPartId=-1|Location.X=1655|Location.Y=20|FontID=7|Text==SheetTotal
|RECORD=4|OwnerIndex=1|IndexInSheet=79|OwnerPartId=-1|Location.X=1323|Location.Y=100|Justification=3|FontID=4|Text=TITLE
|RECORD=4|OwnerIndex=1|IndexInSheet=80|OwnerPartId=-1|Location.X=1328|Location.Y=60|Justification=3|FontID=4|Text=SIZE
|RECORD=4|OwnerIndex=1|IndexInSheet=81|OwnerPartId=-1|Location.X=1407|Location.Y=60|Justification=3|FontID=4|Text=DWG NO.
|RECORD=4|OwnerIndex=1|IndexInSheet=82|OwnerPartId=-1|Location.X=1387|Location.Y=30|Justification=3|FontID=4|Text=FILE NAME
|RECORD=4|OwnerIndex=1|IndexInSheet=83|OwnerPartId=-1|Location.X=1582|Location.Y=30|Justification=3|FontID=4|Text=SHEET
|RECORD=4|OwnerIndex=1|IndexInSheet=84|OwnerPartId=-1|Location.X=1640|Location.Y=30|Justification=3|FontID=4|Text=OF
|RECORD=4|OwnerIndex=1|IndexInSheet=85|OwnerPartId=-1|Location.X=1657|Location.Y=60|Justification=3|FontID=4|Text=REV
|RECORD=6|OwnerIndex=1|IndexInSheet=86|OwnerPartId=-1|LocationCount=2|X1=1385|Y1=35|X2=1385|Y2=20
|RECORD=4|OwnerIndex=1|IndexInSheet=87|OwnerPartId=-1|Location.X=1322|Location.Y=30|Justification=3|FontID=4|Text=SCALE:
|RECORD=4|OwnerIndex=1|IndexInSheet=88|OwnerPartId=-1|Location.X=1349|Location.Y=20|FontID=7|Text==SCH_SCALE
|RECORD=6|OwnerIndex=1|IndexInSheet=89|OwnerPartId=-1|LocationCount=2|X1=1580|Y1=35|X2=1580|Y2=20
|RECORD=4|OwnerIndex=1|IndexInSheet=90|OwnerPartId=-1|Location.X=1355|Location.Y=40|FontID=9|Text==CAGE_CODE
|RECORD=4|OwnerIndex=1|IndexInSheet=91|OwnerPartId=-1|Location.X=1352|Location.Y=56|FontID=4|Text=CAGE CODE
|RECORD=6|OwnerIndex=1|IndexInSheet=92|OwnerPartId=-1|LocationCount=2|X1=1350|Y1=65|X2=1350|Y2=35
|RECORD=6|OwnerIndex=1|IndexInSheet=93|OwnerPartId=-1|LineWidth=1|LocationCount=2|X1=1680|Y1=120|X2=1320|Y2=120
|RECORD=6|OwnerIndex=1|IndexInSheet=94|OwnerPartId=-1|LineWidth=1|LocationCount=2|X1=1680|Y1=160|X2=1320|Y2=160
|RECORD=4|OwnerIndex=1|IndexInSheet=95|OwnerPartId=-1|Location.X=1323|Location.Y=150|FontID=4|Text=PROJECT
|RECORD=6|OwnerIndex=1|IndexInSheet=96|OwnerPartId=-1|LocationCount=2|X1=1390|Y1=160|X2=1390|Y2=120
|RECORD=4|OwnerIndex=1|IndexInSheet=97|OwnerPartId=-1|Location.X=1325|Location.Y=130|FontID=9|Text==Project
|RECORD=4|OwnerIndex=1|IndexInSheet=98|OwnerPartId=-1|Location.X=1613|Location.Y=129|Justification=2|FontID=10|Text==Address3|IsMirrored=T
|RECORD=4|OwnerIndex=1|IndexInSheet=99|OwnerPartId=-1|Location.X=1614|Location.Y=120|Justification=2|FontID=10|Text==Address4|IsMirrored=T
|RECORD=4|OwnerIndex=1|IndexInSheet=100|OwnerPartId=-1|Location.X=1614|Location.Y=150|Justification=2|FontID=10|Text==Address1|IsMirrored=T
|RECORD=4|OwnerIndex=1|IndexInSheet=101|OwnerPartId=-1|Location.X=1614|Location.Y=144|Justification=5|FontID=10|Text==Address2|IsMirrored=T
|RECORD=6|OwnerIndex=1|IndexInSheet=102|OwnerPartId=1|LineWidth=1|LocationCount=2|X1=1320|Y1=65|X2=1320|Y2=35
|RECORD=6|OwnerIndex=1|IndexInSheet=103|OwnerPartId=1|LineWidth=1|LocationCount=2|X1=1320|Y1=35|X2=1320|Y2=20
|RECORD=6|OwnerIndex=1|IndexInSheet=104|OwnerPartId=1|LineWidth=1|LocationCount=2|X1=1320|Y1=65|X2=1320|Y2=120
|RECORD=6|OwnerIndex=1|IndexInSheet=105|OwnerPartId=1|LineWidth=1|LocationCount=2|X1=1320|Y1=120|X2=1320|Y2=160
|RECORD=6|OwnerIndex=1|IndexInSheet=106|OwnerPartId=1|LineWidth=1|LocationCount=3|X1=1320|Y1=160|X2=1180|Y2=160|X3=1180|Y3=20
|RECORD=4|OwnerIndex=1|IndexInSheet=107|OwnerPartId=1|Location.X=1212|Location.Y=145|FontID=4|Text=APPROVALS
|RECORD=4|OwnerIndex=1|IndexInSheet=108|OwnerPartId=1|Location.X=1290|Location.Y=145|FontID=4|Text=DATE
|RECORD=4|OwnerIndex=1|IndexInSheet=109|OwnerPartId=1|Location.X=1182|Location.Y=131|FontID=4|Text=ENG:
|RECORD=4|OwnerIndex=1|IndexInSheet=110|OwnerPartId=1|Location.X=1182|Location.Y=116|FontID=4|Text=DSN:
|RECORD=6|OwnerIndex=1|IndexInSheet=111|OwnerPartId=1|LocationCount=2|X1=1180|Y1=125|X2=1320|Y2=125
|RECORD=6|OwnerIndex=1|IndexInSheet=112|OwnerPartId=1|LocationCount=2|X1=1180|Y1=140|X2=1320|Y2=140
|RECORD=6|OwnerIndex=1|IndexInSheet=113|OwnerPartId=1|LocationCount=2|X1=1280|Y1=160|X2=1280|Y2=95
|RECORD=4|OwnerIndex=1|IndexInSheet=114|OwnerPartId=1|Location.X=1210|Location.Y=125|FontID=4|Text==Engineer
|RECORD=4|OwnerIndex=1|IndexInSheet=115|OwnerPartId=1|Location.X=1210|Location.Y=110|FontID=4|Text==DrawnBy
|RECORD=4|OwnerIndex=1|IndexInSheet=116|OwnerPartId=1|Location.X=1285|Location.Y=125|FontID=4|Text==ENG_APP_DATE
|RECORD=4|OwnerIndex=1|IndexInSheet=117|OwnerPartId=1|Location.X=1285|Location.Y=110|FontID=4|Text==DSN_APP_DATE
|RECORD=6|OwnerIndex=1|IndexInSheet=118|OwnerPartId=1|LineWidth=1|LocationCount=2|X1=1180|Y1=95|X2=1320|Y2=95
|RECORD=6|OwnerIndex=1|IndexInSheet=119|OwnerPartId=1|LocationCount=2|X1=1180|Y1=110|X2=1320|Y2=110
|RECORD=4|OwnerIndex=1|IndexInSheet=120|OwnerPartId=1|Location.X=1182|Location.Y=101|FontID=4|Text=CHK:
|RECORD=4|OwnerIndex=1|IndexInSheet=121|OwnerPartId=1|Location.X=1285|Location.Y=95|FontID=4|Text==CHK_APP_DATE
|RECORD=6|OwnerIndex=1|IndexInSheet=122|OwnerPartId=1|LocationCount=2|X1=1180|Y1=65|X2=1320|Y2=65
|RECORD=6|OwnerIndex=1|IndexInSheet=123|OwnerPartId=1|LocationCount=2|X1=1180|Y1=80|X2=1320|Y2=80
|RECORD=6|OwnerIndex=1|IndexInSheet=124|OwnerPartId=1|LocationCount=2|X1=1180|Y1=35|X2=1320|Y2=35
|RECORD=6|OwnerIndex=1|IndexInSheet=125|OwnerPartId=1|LocationCount=2|X1=1180|Y1=50|X2=1320|Y2=50
|RECORD=4|OwnerIndex=1|IndexInSheet=126|OwnerPartId=-1|Location.X=1204|Location.Y=82|FontID=4|Text=REFERENCE DOCUMENTS
|RECORD=4|OwnerIndex=1|IndexInSheet=127|OwnerPartId=1|Location.X=1182|Location.Y=71|FontID=4|Text=BOM:
|RECORD=4|OwnerIndex=1|IndexInSheet=128|OwnerPartId=1|Location.X=1183|Location.Y=56|FontID=4|Text=ASSY DWG:
|RECORD=4|OwnerIndex=1|IndexInSheet=129|OwnerPartId=1|Location.X=1182|Location.Y=41|FontID=4|Text=FAB DWG:
|RECORD=4|OwnerIndex=1|IndexInSheet=130|OwnerPartId=1|Location.X=1182|Location.Y=26|FontID=4|Text=PCB DWG:
|RECORD=4|OwnerIndex=1|IndexInSheet=131|OwnerPartId=-1|Location.X=1228|Location.Y=22|FontID=5|Text==PCB_DWG_NO
|RECORD=4|OwnerIndex=1|IndexInSheet=132|OwnerPartId=-1|Location.X=1228|Location.Y=37|FontID=5|Text==DOC_NO_FAB_DWG
|RECORD=4|OwnerIndex=1|IndexInSheet=133|OwnerPartId=-1|Location.X=1228|Location.Y=52|FontID=5|Text==DOC_NO_ASSY_DWG
|RECORD=4|OwnerIndex=1|IndexInSheet=134|OwnerPartId=-1|Location.X=1228|Location.Y=68|FontID=5|Text==DOC_NO_BOM
|RECORD=4|OwnerIndex=1|IndexInSheet=135|OwnerPartId=1|Location.X=1210|Location.Y=96|FontID=4|Text==CheckedBy
|RECORD=4|OwnerIndex=1|IndexInSheet=136|OwnerPartId=-1|Location.X=1591|Location.Y=104|FontID=7|Text==Item
|RECORD=6|OwnerIndex=1|IndexInSheet=137|OwnerPartId=-1|LineWidth=1|LocationCount=2|X1=1320|Y1=105|X2=1680|Y2=105
|RECORD=4|OwnerIndex=1|IndexInSheet=138|OwnerPartId=-1|Location.X=1322|Location.Y=115|Justification=3|FontID=4|Text=PROJECT REVISION:
|RECORD=4|OwnerIndex=1|IndexInSheet=139|OwnerPartId=-1|Location.X=1542|Location.Y=116|Justification=3|FontID=4|Text=DESIGN ITEM:
|RECORD=4|OwnerIndex=1|IndexInSheet=140|OwnerPartId=-1|Location.X=1432|Location.Y=116|Justification=3|FontID=4|Text=DOCUMENT REVISION:
|RECORD=6|OwnerIndex=1|IndexInSheet=141|OwnerPartId=-1|LocationCount=2|X1=1430|Y1=120|X2=1430|Y2=105
|RECORD=6|OwnerIndex=1|IndexInSheet=142|OwnerPartId=-1|LocationCount=2|X1=1541|Y1=120|X2=1541|Y2=105
|RECORD=4|OwnerIndex=1|IndexInSheet=143|OwnerPartId=-1|Location.X=1392|Location.Y=104|FontID=7|Text==VersionControl_ProjFolderRevNumber
|RECORD=4|OwnerIndex=1|IndexInSheet=144|OwnerPartId=-1|Location.X=1511|Location.Y=104|FontID=7|Text==VersionControl_RevNumber
|RECORD=6|OwnerIndex=1|IndexInSheet=145|OwnerPartId=-1|LineWidth=1|LocationCount=2|X1=1320|Y1=65|X2=1680|Y2=65
|RECORD=4|OwnerIndex=1|IndexInSheet=146|OwnerPartId=-1|Location.X=1662|Location.Y=41|FontID=7|Text==ItemRevision
|RECORD=30|OwnerIndex=1|IndexInSheet=147|OwnerPartId=-1|Location.X=1398|Location.Y=123|Corner.X=1558|Corner.X_Frac=41666|Corner.Y=158|KeepAspect=T|EmbedImage=T|FileName=Z:\Altium Project Template\Altium Logo\Altm black.jpg
|RECORD=17|IndexInSheet=1|OwnerPartId=-1|ShowNetName=T|Location.X=880|Location.Y=830|Orientation=1|Color=128|FontID=1|Text=+3.3V
|RECORD=17|IndexInSheet=2|OwnerPartId=-1|ShowNetName=T|Location.X=780|Location.Y=830|Orientation=1|Color=128|FontID=1|Text=+3.3V
|RECORD=17|IndexInSheet=3|OwnerPartId=-1|ShowNetName=T|Location.X=680|Location.Y=830|Orientation=1|Color=128|FontID=1|Text=+3.3V
|RECORD=17|IndexInSheet=4|OwnerPartId=-1|ShowNetName=T|Location.X=580|Location.Y=825|Orientation=1|Color=128|FontID=1|Text=+3.3V
|RECORD=17|IndexInSheet=5|OwnerPartId=-1|ShowNetName=T|Location.X=571|Location.Y=669|Orientation=2|Color=255|FontID=1|Text=LED1|IsCrossSheetConnector=T
|RECORD=17|IndexInSheet=6|OwnerPartId=-1|ShowNetName=T|Location.X=671|Location.Y=669|Orientation=2|Color=255|FontID=1|Text=LED2|IsCrossSheetConnector=T
|RECORD=17|IndexInSheet=7|OwnerPartId=-1|ShowNetName=T|Location.X=771|Location.Y=669|Orientation=2|Color=255|FontID=1|Text=LED3|IsCrossSheetConnector=T
|RECORD=17|IndexInSheet=8|OwnerPartId=-1|ShowNetName=T|Location.X=871|Location.Y=669|Orientation=2|Color=255|FontID=1|Text=LED4|IsCrossSheetConnector=T
|RECORD=4|IndexInSheet=9|OwnerPartId=-1|Location.X=631|Location.Y=849|Color=8388608|FontID=6|Text=SYSTEM STATUS LEDS
|RECORD=1|LibReference=RES|ComponentDescription=ERJ-3EKF2000V|PartCount=2|DisplayModeCount=2|IndexInSheet=10|OwnerPartId=-1|Location.X=570|Location.Y=700|Orientation=1|CurrentPartId=1|SourceLibraryName=Altium Content Vault|TargetFileName=*|AreaColor=11599871|Color=128|PartIDLocked=F|DesignItemId=CMP-2000-00316-1|AllPinCount=2
|RECORD=2|OwnerIndex=159|OwnerPartId=1|OwnerPartDisplayMode=1|FormalType=1|Electrical=4|PinConglomerate=33|PinLength=10|Location.X=580|Location.Y=720|Name=2|Designator=2|PinPropagationDelay=0.000000E+000
|RECORD=2|OwnerIndex=159|OwnerPartId=1|OwnerPartDisplayMode=1|FormalType=1|Electrical=4|PinConglomerate=35|PinLength=10|Location.X=580|Location.Y=700|Name=1|Designator=1|PinPropagationDelay=0.000000E+000
|RECORD=14|OwnerIndex=159|IsNotAccesible=T|IndexInSheet=2|OwnerPartId=1|OwnerPartDisplayMode=1|Location.X=576|Location.Y=700|Corner.X=584|Corner.Y=720|LineWidth=1|Color=16711680|AreaColor=11599871
|RECORD=2|OwnerIndex=159|OwnerPartId=1|FormalType=1|Electrical=4|PinConglomerate=33|PinLength=10|Location.X=580|Location.Y=720|Name=2|Designator=2|PinPropagationDelay=0.000000E+000
|RECORD=2|OwnerIndex=159|OwnerPartId=1|FormalType=1|Electrical=4|PinConglomerate=35|PinLength=10|Location.X=580|Location.Y=700|Name=1|Designator=1|PinPropagationDelay=0.000000E+000
|RECORD=6|OwnerIndex=159|IsNotAccesible=T|IndexInSheet=5|OwnerPartId=1|LineWidth=1|Color=16711680|LocationCount=10|X1=580|Y1=720|X2=580|Y2=716|X3=582|Y3=715|X4=578|Y4=713|X5=582|Y5=711|X6=578|Y6=709|X7=582|Y7=707|X8=578|Y8=705|X9=580|Y9=704|X10=580|Y10=700
|RECORD=41|OwnerIndex=159|IndexInSheet=6|OwnerPartId=-1|Location.X=577|Location.Y=732|Color=8388608|FontID=1|IsHidden=T|Text=Panasonic|Name=Manufacturer
|RECORD=41|OwnerIndex=159|IndexInSheet=7|OwnerPartId=-1|Location.X=577|Location.Y=732|Color=8388608|FontID=1|IsHidden=T|Text=ERJ-3EKF2000V|Name=Part Number
|RECORD=34|OwnerIndex=159|IndexInSheet=-1|OwnerPartId=-1|Location.X=583|Location.Y=711|Color=8388608|FontID=1|Text=R35|Name=Designator|ReadOnlyState=1
|RECORD=41|OwnerIndex=159|IndexInSheet=-1|OwnerPartId=-1|Location.X=583|Location.Y=701|Color=8388608|FontID=1|Text=200 OHM|Name=Comment
|RECORD=44|OwnerIndex=159
|RECORD=45|OwnerIndex=174|IndexInSheet=-1|Description=Chip Resistor, 2-Leads, Body 1.60x0.80mm, IPC Medium Density|UseComponentLibrary=T|ModelName=RESC1608X55X30NL15T15|ModelType=PCBLIB|DatafileCount=1|ModelDatafileEntity0=RESC1608X55X30NL15T15|ModelDatafileKind0=PCBLib|IsCurrent=T|DatalinksLocked=T|DatabaseDatalinksLocked=T
|RECORD=46|OwnerIndex=175
|RECORD=48|OwnerIndex=175
|RECORD=41|OwnerIndex=177|IndexInSheet=-1|OwnerPartId=-1|Color=8388608|FontID=1|Text=2D|Name=Available Preview Images
|RECORD=45|OwnerIndex=174|IndexInSheet=-1|Description=Chip Resistor, 2-Leads, Body 1.60x0.80mm, IPC Low Density|UseComponentLibrary=T|ModelName=RESC1608X55X30ML15T15|ModelType=PCBLIB|DatafileCount=1|ModelDatafileEntity0=RESC1608X55X30ML15T15|ModelDatafileKind0=PCBLib|DatalinksLocked=T|DatabaseDatalinksLocked=T
|RECORD=46|OwnerIndex=179
|RECORD=48|OwnerIndex=179
|RECORD=41|OwnerIndex=181|IndexInSheet=-1|OwnerPartId=-1|Color=8388608|FontID=1|Text=2D|Name=Available Preview Images
|RECORD=45|OwnerIndex=174|IndexInSheet=-1|Description=Chip Resistor, 2-Leads, Body 1.60x0.80mm, IPC High Density|UseComponentLibrary=T|ModelName=RESC1608X55X30LL15T15|ModelType=PCBLIB|DatafileCount=1|ModelDatafileEntity0=RESC1608X55X30LL15T15|ModelDatafileKind0=PCBLib|DatalinksLocked=T|DatabaseDatalinksLocked=T
|RECORD=46|OwnerIndex=183
|RECORD=48|OwnerIndex=183
|RECORD=41|OwnerIndex=185|IndexInSheet=-1|OwnerPartId=-1|Color=8388608|FontID=1|Text=2D|Name=Available Preview Images
|RECORD=1|LibReference=RES|ComponentDescription=ERJ-3EKF2000V|PartCount=2|DisplayModeCount=2|IndexInSheet=11|OwnerPartId=-1|Location.X=670|Location.Y=700|Orientation=1|CurrentPartId=1|SourceLibraryName=Altium Content Vault|TargetFileName=*|AreaColor=11599871|Color=128|PartIDLocked=F|DesignItemId=CMP-2000-00316-1|AllPinCount=2
|RECORD=2|OwnerIndex=187|OwnerPartId=1|OwnerPartDisplayMode=1|FormalType=1|Electrical=4|PinConglomerate=33|PinLength=10|Location.X=680|Location.Y=720|Name=2|Designator=2|PinPropagationDelay=0.000000E+000
|RECORD=2|OwnerIndex=187|OwnerPartId=1|OwnerPartDisplayMode=1|FormalType=1|Electrical=4|PinConglomerate=35|PinLength=10|Location.X=680|Location.Y=700|Name=1|Designator=1|PinPropagationDelay=0.000000E+000
|RECORD=14|OwnerIndex=187|IsNotAccesible=T|IndexInSheet=2|OwnerPartId=1|OwnerPartDisplayMode=1|Location.X=676|Location.Y=700|Corner.X=684|Corner.Y=720|LineWidth=1|Color=16711680|AreaColor=11599871
|RECORD=2|OwnerIndex=187|OwnerPartId=1|FormalType=1|Electrical=4|PinConglomerate=33|PinLength=10|Location.X=680|Location.Y=720|Name=2|Designator=2|PinPropagationDelay=0.000000E+000
|RECORD=2|OwnerIndex=187|OwnerPartId=1|FormalType=1|Electrical=4|PinConglomerate=35|PinLength=10|Location.X=680|Location.Y=700|Name=1|Designator=1|PinPropagationDelay=0.000000E+000
|RECORD=6|OwnerIndex=187|IsNotAccesible=T|IndexInSheet=5|OwnerPartId=1|LineWidth=1|Color=16711680|LocationCount=10|X1=680|Y1=720|X2=680|Y2=716|X3=682|Y3=715|X4=678|Y4=713|X5=682|Y5=711|X6=678|Y6=709|X7=682|Y7=707|X8=678|Y8=705|X9=680|Y9=704|X10=680|Y10=700
|RECORD=41|OwnerIndex=187|IndexInSheet=6|OwnerPartId=-1|Location.X=677|Location.Y=732|Color=8388608|FontID=1|IsHidden=T|Text=Panasonic|Name=Manufacturer
|RECORD=41|OwnerIndex=187|IndexInSheet=7|OwnerPartId=-1|Location.X=677|Location.Y=732|Color=8388608|FontID=1|IsHidden=T|Text=ERJ-3EKF2000V|Name=Part Number
|RECORD=34|OwnerIndex=187|IndexInSheet=-1|OwnerPartId=-1|Location.X=683|Location.Y=711|Color=8388608|FontID=1|Text=R36|Name=Designator|ReadOnlyState=1
|RECORD=41|OwnerIndex=187|IndexInSheet=-1|OwnerPartId=-1|Location.X=683|Location.Y=701|Color=8388608|FontID=1|Text=200 OHM|Name=Comment
|RECORD=44|OwnerIndex=187
|RECORD=45|OwnerIndex=202|IndexInSheet=-1|Description=Chip Resistor, 2-Leads, Body 1.60x0.80mm, IPC Medium Density|UseComponentLibrary=T|ModelName=RESC1608X55X30NL15T15|ModelType=PCBLIB|DatafileCount=1|ModelDatafileEntity0=RESC1608X55X30NL15T15|ModelDatafileKind0=PCBLib|IsCurrent=T|DatalinksLocked=T|DatabaseDatalinksLocked=T
|RECORD=46|OwnerIndex=203
|RECORD=48|OwnerIndex=203
|RECORD=41|OwnerIndex=205|IndexInSheet=-1|OwnerPartId=-1|Color=8388608|FontID=1|Text=2D|Name=Available Preview Images
|RECORD=45|OwnerIndex=202|IndexInSheet=-1|Description=Chip Resistor, 2-Leads, Body 1.60x0.80mm, IPC Low Density|UseComponentLibrary=T|ModelName=RESC1608X55X30ML15T15|ModelType=PCBLIB|DatafileCount=1|ModelDatafileEntity0=RESC1608X55X30ML15T15|ModelDatafileKind0=PCBLib|DatalinksLocked=T|DatabaseDatalinksLocked=T
|RECORD=46|OwnerIndex=207
|RECORD=48|OwnerIndex=207
|RECORD=41|OwnerIndex=209|IndexInSheet=-1|OwnerPartId=-1|Color=8388608|FontID=1|Text=2D|Name=Available Preview Images
|RECORD=45|OwnerIndex=202|IndexInSheet=-1|Description=Chip Resistor, 2-Leads, Body 1.60x0.80mm, IPC High Density|UseComponentLibrary=T|ModelName=RESC1608X55X30LL15T15|ModelType=PCBLIB|DatafileCount=1|ModelDatafileEntity0=RESC1608X55X30LL15T15|ModelDatafileKind0=PCBLib|DatalinksLocked=T|DatabaseDatalinksLocked=T
|RECORD=46|OwnerIndex=211
|RECORD=48|OwnerIndex=211
|RECORD=41|OwnerIndex=213|IndexInSheet=-1|OwnerPartId=-1|Color=8388608|FontID=1|Text=2D|Name=Available Preview Images
|RECORD=1|LibReference=RES|ComponentDescription=ERJ-3EKF2000V|PartCount=2|DisplayModeCount=2|IndexInSheet=12|OwnerPartId=-1|Location.X=770|Location.Y=700|Orientation=1|CurrentPartId=1|SourceLibraryName=Altium Content Vault|TargetFileName=*|AreaColor=11599871|Color=128|PartIDLocked=F|DesignItemId=CMP-2000-00316-1|AllPinCount=2
|RECORD=2|OwnerIndex=215|OwnerPartId=1|OwnerPartDisplayMode=1|FormalType=1|Electrical=4|PinConglomerate=33|PinLength=10|Location.X=780|Location.Y=720|Name=2|Designator=2|PinPropagationDelay=0.000000E+000
|RECORD=2|OwnerIndex=215|OwnerPartId=1|OwnerPartDisplayMode=1|FormalType=1|Electrical=4|PinConglomerate=35|PinLength=10|Location.X=780|Location.Y=700|Name=1|Designator=1|PinPropagationDelay=0.000000E+000
|RECORD=14|OwnerIndex=215|IsNotAccesible=T|IndexInSheet=2|OwnerPartId=1|OwnerPartDisplayMode=1|Location.X=776|Location.Y=700|Corner.X=784|Corner.Y=720|LineWidth=1|Color=16711680|AreaColor=11599871
|RECORD=2|OwnerIndex=215|OwnerPartId=1|FormalType=1|Electrical=4|PinConglomerate=33|PinLength=10|Location.X=780|Location.Y=720|Name=2|Designator=2|PinPropagationDelay=0.000000E+000
|RECORD=2|OwnerIndex=215|OwnerPartId=1|FormalType=1|Electrical=4|PinConglomerate=35|PinLength=10|Location.X=780|Location.Y=700|Name=1|Designator=1|PinPropagationDelay=0.000000E+000
|RECORD=6|OwnerIndex=215|IsNotAccesible=T|IndexInSheet=5|OwnerPartId=1|LineWidth=1|Color=16711680|LocationCount=10|X1=780|Y1=720|X2=780|Y2=716|X3=782|Y3=715|X4=778|Y4=713|X5=782|Y5=711|X6=778|Y6=709|X7=782|Y7=707|X8=778|Y8=705|X9=780|Y9=704|X10=780|Y10=700
|RECORD=41|OwnerIndex=215|IndexInSheet=6|OwnerPartId=-1|Location.X=777|Location.Y=732|Color=8388608|FontID=1|IsHidden=T|Text=Panasonic|Name=Manufacturer
|RECORD=41|OwnerIndex=215|IndexInSheet=7|OwnerPartId=-1|Location.X=777|Location.Y=732|Color=8388608|FontID=1|IsHidden=T|Text=ERJ-3EKF2000V|Name=Part Number
|RECORD=34|OwnerIndex=215|IndexInSheet=-1|OwnerPartId=-1|Location.X=783|Location.Y=711|Color=8388608|FontID=1|Text=R38|Name=Designator|ReadOnlyState=1
|RECORD=41|OwnerIndex=215|IndexInSheet=-1|OwnerPartId=-1|Location.X=783|Location.Y=701|Color=8388608|FontID=1|Text=200 OHM|Name=Comment
|RECORD=44|OwnerIndex=215
|RECORD=45|OwnerIndex=230|IndexInSheet=-1|Description=Chip Resistor, 2-Leads, Body 1.60x0.80mm, IPC Medium Density|UseComponentLibrary=T|ModelName=RESC1608X55X30NL15T15|ModelType=PCBLIB|DatafileCount=1|ModelDatafileEntity0=RESC1608X55X30NL15T15|ModelDatafileKind0=PCBLib|IsCurrent=T|DatalinksLocked=T|DatabaseDatalinksLocked=T
|RECORD=46|OwnerIndex=231
|RECORD=48|OwnerIndex=231
|RECORD=41|OwnerIndex=233|IndexInSheet=-1|OwnerPartId=-1|Color=8388608|FontID=1|Text=2D|Name=Available Preview Images
|RECORD=45|OwnerIndex=230|IndexInSheet=-1|Description=Chip Resistor, 2-Leads, Body 1.60x0.80mm, IPC Low Density|UseComponentLibrary=T|ModelName=RESC1608X55X30ML15T15|ModelType=PCBLIB|DatafileCount=1|ModelDatafileEntity0=RESC1608X55X30ML15T15|ModelDatafileKind0=PCBLib|DatalinksLocked=T|DatabaseDatalinksLocked=T
|RECORD=46|OwnerIndex=235
|RECORD=48|OwnerIndex=235
|RECORD=41|OwnerIndex=237|IndexInSheet=-1|OwnerPartId=-1|Color=8388608|FontID=1|Text=2D|Name=Available Preview Images
|RECORD=45|OwnerIndex=230|IndexInSheet=-1|Description=Chip Resistor, 2-Leads, Body 1.60x0.80mm, IPC High Density|UseComponentLibrary=T|ModelName=RESC1608X55X30LL15T15|ModelType=PCBLIB|DatafileCount=1|ModelDatafileEntity0=RESC1608X55X30LL15T15|ModelDatafileKind0=PCBLib|DatalinksLocked=T|DatabaseDatalinksLocked=T
|RECORD=46|OwnerIndex=239
|RECORD=48|OwnerIndex=239
|RECORD=41|OwnerIndex=241|IndexInSheet=-1|OwnerPartId=-1|Color=8388608|FontID=1|Text=2D|Name=Available Preview Images
|RECORD=1|LibReference=RES|ComponentDescription=ERJ-3EKF2000V|PartCount=2|DisplayModeCount=2|IndexInSheet=13|OwnerPartId=-1|Location.X=870|Location.Y=700|Orientation=1|CurrentPartId=1|SourceLibraryName=Altium Content Vault|TargetFileName=*|AreaColor=11599871|Color=128|PartIDLocked=F|DesignItemId=CMP-2000-00316-1|AllPinCount=2
|RECORD=2|OwnerIndex=243|OwnerPartId=1|OwnerPartDisplayMode=1|FormalType=1|Electrical=4|PinConglomerate=33|PinLength=10|Location.X=880|Location.Y=720|Name=2|Designator=2|PinPropagationDelay=0.000000E+000
|RECORD=2|OwnerIndex=243|OwnerPartId=1|OwnerPartDisplayMode=1|FormalType=1|Electrical=4|PinConglomerate=35|PinLength=10|Location.X=880|Location.Y=700|Name=1|Designator=1|PinPropagationDelay=0.000000E+000
|RECORD=14|OwnerIndex=243|IsNotAccesible=T|IndexInSheet=2|OwnerPartId=1|OwnerPartDisplayMode=1|Location.X=876|Location.Y=700|Corner.X=884|Corner.Y=720|LineWidth=1|Color=16711680|AreaColor=11599871
|RECORD=2|OwnerIndex=243|OwnerPartId=1|FormalType=1|Electrical=4|PinConglomerate=33|PinLength=10|Location.X=880|Location.Y=720|Name=2|Designator=2|PinPropagationDelay=0.000000E+000
|RECORD=2|OwnerIndex=243|OwnerPartId=1|FormalType=1|Electrical=4|PinConglomerate=35|PinLength=10|Location.X=880|Location.Y=700|Name=1|Designator=1|PinPropagationDelay=0.000000E+000
|RECORD=6|OwnerIndex=243|IsNotAccesible=T|IndexInSheet=5|OwnerPartId=1|LineWidth=1|Color=16711680|LocationCount=10|X1=880|Y1=720|X2=880|Y2=716|X3=882|Y3=715|X4=878|Y4=713|X5=882|Y5=711|X6=878|Y6=709|X7=882|Y7=707|X8=878|Y8=705|X9=880|Y9=704|X10=880|Y10=700
|RECORD=41|OwnerIndex=243|IndexInSheet=6|OwnerPartId=-1|Location.X=877|Location.Y=732|Color=8388608|FontID=1|IsHidden=T|Text=Panasonic|Name=Manufacturer
|RECORD=41|OwnerIndex=243|IndexInSheet=7|OwnerPartId=-1|Location.X=877|Location.Y=732|Color=8388608|FontID=1|IsHidden=T|Text=ERJ-3EKF2000V|Name=Part Number
|RECORD=34|OwnerIndex=243|IndexInSheet=-1|OwnerPartId=-1|Location.X=883|Location.Y=711|Color=8388608|FontID=1|Text=R39|Name=Designator|ReadOnlyState=1
|RECORD=41|OwnerIndex=243|IndexInSheet=-1|OwnerPartId=-1|Location.X=883|Location.Y=701|Color=8388608|FontID=1|Text=200 OHM|Name=Comment
|RECORD=44|OwnerIndex=243
|RECORD=45|OwnerIndex=258|IndexInSheet=-1|Description=Chip Resistor, 2-Leads, Body 1.60x0.80mm, IPC Medium Density|UseComponentLibrary=T|ModelName=RESC1608X55X30NL15T15|ModelType=PCBLIB|DatafileCount=1|ModelDatafileEntity0=RESC1608X55X30NL15T15|ModelDatafileKind0=PCBLib|IsCurrent=T|DatalinksLocked=T|DatabaseDatalinksLocked=T
|RECORD=46|OwnerIndex=259
|RECORD=48|OwnerIndex=259
|RECORD=41|OwnerIndex=261|IndexInSheet=-1|OwnerPartId=-1|Color=8388608|FontID=1|Text=2D|Name=Available Preview Images
|RECORD=45|OwnerIndex=258|IndexInSheet=-1|Description=Chip Resistor, 2-Leads, Body 1.60x0.80mm, IPC Low Density|UseComponentLibrary=T|ModelName=RESC1608X55X30ML15T15|ModelType=PCBLIB|DatafileCount=1|ModelDatafileEntity0=RESC1608X55X30ML15T15|ModelDatafileKind0=PCBLib|DatalinksLocked=T|DatabaseDatalinksLocked=T
|RECORD=46|OwnerIndex=263
|RECORD=48|OwnerIndex=263
|RECORD=41|OwnerIndex=265|IndexInSheet=-1|OwnerPartId=-1|Color=8388608|FontID=1|Text=2D|Name=Available Preview Images
|RECORD=45|OwnerIndex=258|IndexInSheet=-1|Description=Chip Resistor, 2-Leads, Body 1.60x0.80mm, IPC High Density|UseComponentLibrary=T|ModelName=RESC1608X55X30LL15T15|ModelType=PCBLIB|DatafileCount=1|ModelDatafileEntity0=RESC1608X55X30LL15T15|ModelDatafileKind0=PCBLib|DatalinksLocked=T|DatabaseDatalinksLocked=T
|RECORD=46|OwnerIndex=267
|RECORD=48|OwnerIndex=267
|RECORD=41|OwnerIndex=269|IndexInSheet=-1|OwnerPartId=-1|Color=8388608|FontID=1|Text=2D|Name=Available Preview Images
|RECORD=1|LibReference=155124M173200|ComponentDescription=LED (Multiple)|PartCount=2|DisplayModeCount=1|IndexInSheet=14|OwnerPartId=-1|Location.X=1194|Location.Y=515|IsMirrored=T|CurrentPartId=1|LibraryPath=*|SourceLibraryName=SamacSys.SchLib|TargetFileName=*|AreaColor=11599871|Color=128|PartIDLocked=T|DesignItemId=155124M173200|AllPinCount=4
|RECORD=41|OwnerIndex=271|OwnerPartId=-1|Location.X=1112|Location.Y=515|Color=8388608|FontID=3|IsHidden=T|Text=https://www.mouser.com/ds/2/445/155124M173200-1113601.pdf|Name=Datasheet Link|IsMirrored=T
|RECORD=41|OwnerIndex=271|IndexInSheet=1|OwnerPartId=-1|Location.X=1112|Location.Y=515|Color=8388608|FontID=1|IsHidden=T|Text=Wurth Elektronik|Name=Manufacturer_Name|IsMirrored=T
|RECORD=41|OwnerIndex=271|IndexInSheet=2|OwnerPartId=-1|Location.X=1112|Location.Y=515|Color=8388608|FontID=1|IsHidden=T|Text=155124M173200|Name=Manufacturer_Part_Number|IsMirrored=T
|RECORD=41|OwnerIndex=271|IndexInSheet=3|OwnerPartId=-1|Location.X=1112|Location.Y=515|Color=8388608|FontID=1|IsHidden=T|Text=710-155124M173200|Name=Mouser Part Number|IsMirrored=T
|RECORD=41|OwnerIndex=271|IndexInSheet=4|OwnerPartId=-1|Location.X=1112|Location.Y=515|Color=8388608|FontID=3|IsHidden=T|Text=https://www.mouser.co.uk/ProductDetail/Wurth-Elektronik/155124M173200?qs=5aG0NVq1C4xPhoUU07x4gQ%3D%3D|Name=Mouser Price/Stock|IsMirrored=T
|RECORD=41|OwnerIndex=271|IndexInSheet=5|OwnerPartId=-1|Location.X=1112|Location.Y=515|Color=8388608|FontID=1|IsHidden=T|Name=Arrow Part Number|IsMirrored=T
|RECORD=41|OwnerIndex=271|IndexInSheet=6|OwnerPartId=-1|Location.X=1112|Location.Y=515|Color=8388608|FontID=1|IsHidden=T|Name=Arrow Price/Stock|IsMirrored=T
|RECORD=14|OwnerIndex=271|IsNotAccesible=T|IndexInSheet=7|OwnerPartId=1|Location.X=1134|Location.Y=475|Corner.X=1194|Corner.Y=515|LineWidth=1|Color=128|AreaColor=11599871|IsSolid=T
|RECORD=2|OwnerIndex=271|OwnerPartId=1|FormalType=1|Electrical=7|PinConglomerate=56|PinLength=20|Location.X=1194|Location.Y=505|Name=ANODE|Designator=1|SwapIDPart=Ž&Ž||PinPropagationDelay=0.000000E+000
|RECORD=2|OwnerIndex=271|OwnerPartId=1|FormalType=1|Electrical=2|PinConglomerate=58|PinLength=20|Location.X=1134|Location.Y=485|Name=B|Designator=2|SwapIDPart=Ž&Ž||PinPropagationDelay=0.000000E+000
|RECORD=2|OwnerIndex=271|OwnerPartId=1|FormalType=1|Electrical=2|PinConglomerate=58|PinLength=20|Location.X=1134|Location.Y=495|Name=G|Designator=3|SwapIDPart=Ž&Ž||PinPropagationDelay=0.000000E+000
|RECORD=2|OwnerIndex=271|OwnerPartId=1|FormalType=1|Electrical=2|PinConglomerate=58|PinLength=20|Location.X=1134|Location.Y=505|Name=R|Designator=4|SwapIDPart=Ž&Ž||PinPropagationDelay=0.000000E+000
|RECORD=34|OwnerIndex=271|IndexInSheet=-1|OwnerPartId=-1|Location.X=1134|Location.Y=515|Color=8388608|FontID=1|Text=D13|Name=Designator|ReadOnlyState=1|IsMirrored=T
|RECORD=41|OwnerIndex=271|IndexInSheet=-1|OwnerPartId=-1|Location.X=1134|Location.Y=465|Color=8388608|FontID=1|Text=155124M173200|Name=Comment|IsMirrored=T
|RECORD=44|OwnerIndex=271
|RECORD=45|OwnerIndex=290|IndexInSheet=-1|ModelName=155124M173200|ModelType=PCBLIB|DatafileCount=1|ModelDatafile0=C:\Users\<user>\Documents\AltiumLL\SamacSys.PcbLib|ModelDatafileEntity0=155124M173200|ModelDatafileKind0=PCBLIB|IsCurrent=T
|RECORD=46|OwnerIndex=291
|RECORD=48|OwnerIndex=291
|RECORD=1|LibReference=155124M173200|ComponentDescription=LED (Multiple)|PartCount=2|DisplayModeCount=1|IndexInSheet=15|OwnerPartId=-1|Location.X=1194|Location.Y=455|IsMirrored=T|CurrentPartId=1|LibraryPath=*|SourceLibraryName=SamacSys.SchLib|TargetFileName=*|AreaColor=11599871|Color=128|PartIDLocked=T|DesignItemId=155124M173200|AllPinCount=4
|RECORD=41|OwnerIndex=294|OwnerPartId=-1|Location.X=1112|Location.Y=455|Color=8388608|FontID=3|IsHidden=T|Text=https://www.mouser.com/ds/2/445/155124M173200-1113601.pdf|Name=Datasheet Link|IsMirrored=T
|RECORD=41|OwnerIndex=294|IndexInSheet=1|OwnerPartId=-1|Location.X=1112|Location.Y=455|Color=8388608|FontID=1|IsHidden=T|Text=Wurth Elektronik|Name=Manufacturer_Name|IsMirrored=T
|RECORD=41|OwnerIndex=294|IndexInSheet=2|OwnerPartId=-1|Location.X=1112|Location.Y=455|Color=8388608|FontID=1|IsHidden=T|Text=155124M173200|Name=Manufacturer_Part_Number|IsMirrored=T
|RECORD=41|OwnerIndex=294|IndexInSheet=3|OwnerPartId=-1|Location.X=1112|Location.Y=455|Color=8388608|FontID=1|IsHidden=T|Text=710-155124M173200|Name=Mouser Part Number|IsMirrored=T
|RECORD=41|OwnerIndex=294|IndexInSheet=4|OwnerPartId=-1|Location.X=1112|Location.Y=455|Color=8388608|FontID=3|IsHidden=T|Text=https://www.mouser.co.uk/ProductDetail/Wurth-Elektronik/155124M173200?qs=5aG0NVq1C4xPhoUU07x4gQ%3D%3D|Name=Mouser Price/Stock|IsMirrored=T
|RECORD=41|OwnerIndex=294|IndexInSheet=5|OwnerPartId=-1|Location.X=1112|Location.Y=455|Color=8388608|FontID=1|IsHidden=T|Name=Arrow Part Number|IsMirrored=T
|RECORD=41|OwnerIndex=294|IndexInSheet=6|OwnerPartId=-1|Location.X=1112|Location.Y=455|Color=8388608|FontID=1|IsHidden=T|Name=Arrow Price/Stock|IsMirrored=T
|RECORD=14|OwnerIndex=294|IsNotAccesible=T|IndexInSheet=7|OwnerPartId=1|Location.X=1134|Location.Y=415|Corner.X=1194|Corner.Y=455|LineWidth=1|Color=128|AreaColor=11599871|IsSolid=T
|RECORD=2|OwnerIndex=294|OwnerPartId=1|FormalType=1|Electrical=7|PinConglomerate=56|PinLength=20|Location.X=1194|Location.Y=445|Name=ANODE|Designator=1|SwapIDPart=Ž&Ž||PinPropagationDelay=0.000000E+000
|RECORD=2|OwnerIndex=294|OwnerPartId=1|FormalType=1|Electrical=2|PinConglomerate=58|PinLength=20|Location.X=1134|Location.Y=425|Name=B|Designator=2|SwapIDPart=Ž&Ž||PinPropagationDelay=0.000000E+000
|RECORD=2|OwnerIndex=294|OwnerPartId=1|FormalType=1|Electrical=2|PinConglomerate=58|PinLength=20|Location.X=1134|Location.Y=435|Name=G|Designator=3|SwapIDPart=Ž&Ž||PinPropagationDelay=0.000000E+000
|RECORD=2|OwnerIndex=294|OwnerPartId=1|FormalType=1|Electrical=2|PinConglomerate=58|PinLength=20|Location.X=1134|Location.Y=445|Name=R|Designator=4|SwapIDPart=Ž&Ž||PinPropagationDelay=0.000000E+000
|RECORD=34|OwnerIndex=294|IndexInSheet=-1|OwnerPartId=-1|Location.X=1134|Location.Y=455|Color=8388608|FontID=1|Text=D14|Name=Designator|ReadOnlyState=1|IsMirrored=T
|RECORD=41|OwnerIndex=294|IndexInSheet=-1|OwnerPartId=-1|Location.X=1134|Location.Y=405|Color=8388608|FontID=1|Text=155124M173200|Name=Comment|IsMirrored=T
|RECORD=44|OwnerIndex=294
|RECORD=45|OwnerIndex=313|IndexInSheet=-1|ModelName=155124M173200|ModelType=PCBLIB|DatafileCount=1|ModelDatafile0=C:\Users\<user>\Documents\AltiumLL\SamacSys.PcbLib|ModelDatafileEntity0=155124M173200|ModelDatafileKind0=PCBLIB|IsCurrent=T
|RECORD=46|OwnerIndex=314
|RECORD=48|OwnerIndex=314
|RECORD=1|LibReference=155124M173200|ComponentDescription=LED (Multiple)|PartCount=2|DisplayModeCount=1|IndexInSheet=16|OwnerPartId=-1|Location.X=1194|Location.Y=395|IsMirrored=T|CurrentPartId=1|LibraryPath=*|SourceLibraryName=SamacSys.SchLib|TargetFileName=*|AreaColor=11599871|Color=128|PartIDLocked=T|DesignItemId=155124M173200|AllPinCount=4
|RECORD=41|OwnerIndex=317|OwnerPartId=-1|Location.X=1112|Location.Y=395|Color=8388608|FontID=3|IsHidden=T|Text=https://www.mouser.com/ds/2/445/155124M173200-1113601.pdf|Name=Datasheet Link|IsMirrored=T
|RECORD=41|OwnerIndex=317|IndexInSheet=1|OwnerPartId=-1|Location.X=1112|Location.Y=395|Color=8388608|FontID=1|IsHidden=T|Text=Wurth Elektronik|Name=Manufacturer_Name|IsMirrored=T
|RECORD=41|OwnerIndex=317|IndexInSheet=2|OwnerPartId=-1|Location.X=1112|Location.Y=395|Color=8388608|FontID=1|IsHidden=T|Text=155124M173200|Name=Manufacturer_Part_Number|IsMirrored=T
|RECORD=41|OwnerIndex=317|IndexInSheet=3|OwnerPartId=-1|Location.X=1112|Location.Y=395|Color=8388608|FontID=1|IsHidden=T|Text=710-155124M173200|Name=Mouser Part Number|IsMirrored=T
|RECORD=41|OwnerIndex=317|IndexInSheet=4|OwnerPartId=-1|Location.X=1112|Location.Y=395|Color=8388608|FontID=3|IsHidden=T|Text=https://www.mouser.co.uk/ProductDetail/Wurth-Elektronik/155124M173200?qs=5aG0NVq1C4xPhoUU07x4gQ%3D%3D|Name=Mouser Price/Stock|IsMirrored=T
|RECORD=41|OwnerIndex=317|IndexInSheet=5|OwnerPartId=-1|Location.X=1112|Location.Y=395|Color=8388608|FontID=1|IsHidden=T|Name=Arrow Part Number|IsMirrored=T
|RECORD=41|OwnerIndex=317|IndexInSheet=6|OwnerPartId=-1|Location.X=1112|Location.Y=395|Color=8388608|FontID=1|IsHidden=T|Name=Arrow Price/Stock|IsMirrored=T
|RECORD=14|OwnerIndex=317|IsNotAccesible=T|IndexInSheet=7|OwnerPartId=1|Location.X=1134|Location.Y=355|Corner.X=1194|Corner.Y=395|LineWidth=1|Color=128|AreaColor=11599871|IsSolid=T
|RECORD=2|OwnerIndex=317|OwnerPartId=1|FormalType=1|Electrical=7|PinConglomerate=56|PinLength=20|Location.X=1194|Location.Y=385|Name=ANODE|Designator=1|SwapIDPart=Ž&Ž||PinPropagationDelay=0.000000E+000
|RECORD=2|OwnerIndex=317|OwnerPartId=1|FormalType=1|Electrical=2|PinConglomerate=58|PinLength=20|Location.X=1134|Location.Y=365|Name=B|Designator=2|SwapIDPart=Ž&Ž||PinPropagationDelay=0.000000E+000
|RECORD=2|OwnerIndex=317|OwnerPartId=1|FormalType=1|Electrical=2|PinConglomerate=58|PinLength=20|Location.X=1134|Location.Y=375|Name=G|Designator=3|SwapIDPart=Ž&Ž||PinPropagationDelay=0.000000E+000
|RECORD=2|OwnerIndex=317|OwnerPartId=1|FormalType=1|Electrical=2|PinConglomerate=58|PinLength=20|Location.X=1134|Location.Y=385|Name=R|Designator=4|SwapIDPart=Ž&Ž||PinPropagationDelay=0.000000E+000
|RECORD=34|OwnerIndex=317|IndexInSheet=-1|OwnerPartId=-1|Location.X=1134|Location.Y=395|Color=8388608|FontID=1|Text=D15|Name=Designator|ReadOnlyState=1|IsMirrored=T
|RECORD=41|OwnerIndex=317|IndexInSheet=-1|OwnerPartId=-1|Location.X=1134|Location.Y=345|Color=8388608|FontID=1|Text=155124M173200|Name=Comment|IsMirrored=T
|RECORD=44|OwnerIndex=317
|RECORD=45|OwnerIndex=336|IndexInSheet=-1|ModelName=155124M173200|ModelType=PCBLIB|DatafileCount=1|ModelDatafile0=C:\Users\<user>\Documents\AltiumLL\SamacSys.PcbLib|ModelDatafileEntity0=155124M173200|ModelDatafileKind0=PCBLIB|IsCurrent=T
|RECORD=46|OwnerIndex=337
|RECORD=48|OwnerIndex=337
|RECORD=1|LibReference=155124M173200|ComponentDescription=LED (Multiple)|PartCount=2|DisplayModeCount=1|IndexInSheet=17|OwnerPartId=-1|Location.X=1194|Location.Y=335|IsMirrored=T|CurrentPartId=1|LibraryPath=*|SourceLibraryName=SamacSys.SchLib|TargetFileName=*|AreaColor=11599871|Color=128|PartIDLocked=T|DesignItemId=155124M173200|AllPinCount=4
|RECORD=41|OwnerIndex=340|OwnerPartId=-1|Location.X=1112|Location.Y=335|Color=8388608|FontID=3|IsHidden=T|Text=https://www.mouser.com/ds/2/445/155124M173200-1113601.pdf|Name=Datasheet Link|IsMirrored=T
|RECORD=41|OwnerIndex=340|IndexInSheet=1|OwnerPartId=-1|Location.X=1112|Location.Y=335|Color=8388608|FontID=1|IsHidden=T|Text=Wurth Elektronik|Name=Manufacturer_Name|IsMirrored=T
|RECORD=41|OwnerIndex=340|IndexInSheet=2|OwnerPartId=-1|Location.X=1112|Location.Y=335|Color=8388608|FontID=1|IsHidden=T|Text=155124M173200|Name=Manufacturer_Part_Number|IsMirrored=T
|RECORD=41|OwnerIndex=340|IndexInSheet=3|OwnerPartId=-1|Location.X=1112|Location.Y=335|Color=8388608|FontID=1|IsHidden=T|Text=710-155124M173200|Name=Mouser Part Number|IsMirrored=T
|RECORD=41|OwnerIndex=340|IndexInSheet=4|OwnerPartId=-1|Location.X=1112|Location.Y=335|Color=8388608|FontID=3|IsHidden=T|Text=https://www.mouser.co.uk/ProductDetail/Wurth-Elektronik/155124M173200?qs=5aG0NVq1C4xPhoUU07x4gQ%3D%3D|Name=Mouser Price/Stock|IsMirrored=T
|RECORD=41|OwnerIndex=340|IndexInSheet=5|OwnerPartId=-1|Location.X=1112|Location.Y=335|Color=8388608|FontID=1|IsHidden=T|Name=Arrow Part Number|IsMirrored=T
|RECORD=41|OwnerIndex=340|IndexInSheet=6|OwnerPartId=-1|Location.X=1112|Location.Y=335|Color=8388608|FontID=1|IsHidden=T|Name=Arrow Price/Stock|IsMirrored=T
|RECORD=14|OwnerIndex=340|IsNotAccesible=T|IndexInSheet=7|OwnerPartId=1|Location.X=1134|Location.Y=295|Corner.X=1194|Corner.Y=335|LineWidth=1|Color=128|AreaColor=11599871|IsSolid=T
|RECORD=2|OwnerIndex=340|OwnerPartId=1|FormalType=1|Electrical=7|PinConglomerate=56|PinLength=20|Location.X=1194|Location.Y=325|Name=ANODE|Designator=1|SwapIDPart=Ž&Ž||PinPropagationDelay=0.000000E+000
|RECORD=2|OwnerIndex=340|OwnerPartId=1|FormalType=1|Electrical=2|PinConglomerate=58|PinLength=20|Location.X=1134|Location.Y=305|Name=B|Designator=2|SwapIDPart=Ž&Ž||PinPropagationDelay=0.000000E+000
|RECORD=2|OwnerIndex=340|OwnerPartId=1|FormalType=1|Electrical=2|PinConglomerate=58|PinLength=20|Location.X=1134|Location.Y=315|Name=G|Designator=3|SwapIDPart=Ž&Ž||PinPropagationDelay=0.000000E+000
|RECORD=2|OwnerIndex=340|OwnerPartId=1|FormalType=1|Electrical=2|PinConglomerate=58|PinLength=20|Location.X=1134|Location.Y=325|Name=R|Designator=4|SwapIDPart=Ž&Ž||PinPropagationDelay=0.000000E+000
|RECORD=34|OwnerIndex=340|IndexInSheet=-1|OwnerPartId=-1|Location.X=1134|Location.Y=335|Color=8388608|FontID=1|Text=D16|Name=Designator|ReadOnlyState=1|IsMirrored=T
|RECORD=41|OwnerIndex=340|IndexInSheet=-1|OwnerPartId=-1|Location.X=1134|Location.Y=285|Color=8388608|FontID=1|Text=155124M173200|Name=Comment|IsMirrored=T
|RECORD=44|OwnerIndex=340
|RECORD=45|OwnerIndex=359|IndexInSheet=-1|ModelName=155124M173200|ModelType=PCBLIB|DatafileCount=1|ModelDatafile0=C:\Users\<user>\Documents\AltiumLL\SamacSys.PcbLib|ModelDatafileEntity0=155124M173200|ModelDatafileKind0=PCBLIB|IsCurrent=T
|RECORD=46|OwnerIndex=360
|RECORD=48|OwnerIndex=360
|RECORD=1|LibReference=155124M173200|ComponentDescription=LED (Multiple)|PartCount=2|DisplayModeCount=1|IndexInSheet=18|OwnerPartId=-1|Location.X=1194|Location.Y=265|IsMirrored=T|CurrentPartId=1|LibraryPath=*|SourceLibraryName=SamacSys.SchLib|TargetFileName=*|AreaColor=11599871|Color=128|PartIDLocked=T|DesignItemId=155124M173200|AllPinCount=4
|RECORD=41|OwnerIndex=363|OwnerPartId=-1|Location.X=1112|Location.Y=265|Color=8388608|FontID=3|IsHidden=T|Text=https://www.mouser.com/ds/2/445/155124M173200-1113601.pdf|Name=Datasheet Link|IsMirrored=T
|RECORD=41|OwnerIndex=363|IndexInSheet=1|OwnerPartId=-1|Location.X=1112|Location.Y=265|Color=8388608|FontID=1|IsHidden=T|Text=Wurth Elektronik|Name=Manufacturer_Name|IsMirrored=T
|RECORD=41|OwnerIndex=363|IndexInSheet=2|OwnerPartId=-1|Location.X=1112|Location.Y=265|Color=8388608|FontID=1|IsHidden=T|Text=155124M173200|Name=Manufacturer_Part_Number|IsMirrored=T
|RECORD=41|OwnerIndex=363|IndexInSheet=3|OwnerPartId=-1|Location.X=1112|Location.Y=265|Color=8388608|FontID=1|IsHidden=T|Text=710-155124M173200|Name=Mouser Part Number|IsMirrored=T
|RECORD=41|OwnerIndex=363|IndexInSheet=4|OwnerPartId=-1|Location.X=1112|Location.Y=265|Color=8388608|FontID=3|IsHidden=T|Text=https://www.mouser.co.uk/ProductDetail/Wurth-Elektronik/155124M173200?qs=5aG0NVq1C4xPhoUU07x4gQ%3D%3D|Name=Mouser Price/Stock|IsMirrored=T
|RECORD=41|OwnerIndex=363|IndexInSheet=5|OwnerPartId=-1|Location.X=1112|Location.Y=265|Color=8388608|FontID=1|IsHidden=T|Name=Arrow Part Number|IsMirrored=T
|RECORD=41|OwnerIndex=363|IndexInSheet=6|OwnerPartId=-1|Location.X=1112|Location.Y=265|Color=8388608|FontID=1|IsHidden=T|Name=Arrow Price/Stock|IsMirrored=T
|RECORD=14|OwnerIndex=363|IsNotAccesible=T|IndexInSheet=7|OwnerPartId=1|Location.X=1134|Location.Y=225|Corner.X=1194|Corner.Y=265|LineWidth=1|Color=128|AreaColor=11599871|IsSolid=T
|RECORD=2|OwnerIndex=363|OwnerPartId=1|FormalType=1|Electrical=7|PinConglomerate=56|PinLength=20|Location.X=1194|Location.Y=255|Name=ANODE|Designator=1|SwapIDPart=Ž&Ž||PinPropagationDelay=0.000000E+000
|RECORD=2|OwnerIndex=363|OwnerPartId=1|FormalType=1|Electrical=2|PinConglomerate=58|PinLength=20|Location.X=1134|Location.Y=235|Name=B|Designator=2|SwapIDPart=Ž&Ž||PinPropagationDelay=0.000000E+000
|RECORD=2|OwnerIndex=363|OwnerPartId=1|FormalType=1|Electrical=2|PinConglomerate=58|PinLength=20|Location.X=1134|Location.Y=245|Name=G|Designator=3|SwapIDPart=Ž&Ž||PinPropagationDelay=0.000000E+000
|RECORD=2|OwnerIndex=363|OwnerPartId=1|FormalType=1|Electrical=2|PinConglomerate=58|PinLength=20|Location.X=1134|Location.Y=255|Name=R|Designator=4|SwapIDPart=Ž&Ž||PinPropagationDelay=0.000000E+000
|RECORD=34|OwnerIndex=363|IndexInSheet=-1|OwnerPartId=-1|Location.X=1134|Location.Y=265|Color=8388608|FontID=1|Text=D17|Name=Designator|ReadOnlyState=1|IsMirrored=T
|RECORD=41|OwnerIndex=363|IndexInSheet=-1|OwnerPartId=-1|Location.X=1134|Location.Y=215|Color=8388608|FontID=1|Text=155124M173200|Name=Comment|IsMirrored=T
|RECORD=44|OwnerIndex=363
|RECORD=45|OwnerIndex=382|IndexInSheet=-1|ModelName=155124M173200|ModelType=PCBLIB|DatafileCount=1|ModelDatafile0=C:\Users\<user>\Documents\AltiumLL\SamacSys.PcbLib|ModelDatafileEntity0=155124M173200|ModelDatafileKind0=PCBLIB|IsCurrent=T
|RECORD=46|OwnerIndex=383
|RECORD=48|OwnerIndex=383
|RECORD=1|LibReference=155124M173200|ComponentDescription=LED (Multiple)|PartCount=2|DisplayModeCount=1|IndexInSheet=19|OwnerPartId=-1|Location.X=1194|Location.Y=195|IsMirrored=T|CurrentPartId=1|LibraryPath=*|SourceLibraryName=SamacSys.SchLib|TargetFileName=*|AreaColor=11599871|Color=128|PartIDLocked=T|DesignItemId=155124M173200|AllPinCount=4
|RECORD=41|OwnerIndex=386|OwnerPartId=-1|Location.X=1112|Location.Y=195|Color=8388608|FontID=3|IsHidden=T|Text=https://www.mouser.com/ds/2/445/155124M173200-1113601.pdf|Name=Datasheet Link|IsMirrored=T
|RECORD=41|OwnerIndex=386|IndexInSheet=1|OwnerPartId=-1|Location.X=1112|Location.Y=195|Color=8388608|FontID=1|IsHidden=T|Text=Wurth Elektronik|Name=Manufacturer_Name|IsMirrored=T
|RECORD=41|OwnerIndex=386|IndexInSheet=2|OwnerPartId=-1|Location.X=1112|Location.Y=195|Color=8388608|FontID=1|IsHidden=T|Text=155124M173200|Name=Manufacturer_Part_Number|IsMirrored=T
|RECORD=41|OwnerIndex=386|IndexInSheet=3|OwnerPartId=-1|Location.X=1112|Location.Y=195|Color=8388608|FontID=1|IsHidden=T|Text=710-155124M173200|Name=Mouser Part Number|IsMirrored=T
|RECORD=41|OwnerIndex=386|IndexInSheet=4|OwnerPartId=-1|Location.X=1112|Location.Y=195|Color=8388608|FontID=3|IsHidden=T|Text=https://www.mouser.co.uk/ProductDetail/Wurth-Elektronik/155124M173200?qs=5aG0NVq1C4xPhoUU07x4gQ%3D%3D|Name=Mouser Price/Stock|IsMirrored=T
|RECORD=41|OwnerIndex=386|IndexInSheet=5|OwnerPartId=-1|Location.X=1112|Location.Y=195|Color=8388608|FontID=1|IsHidden=T|Name=Arrow Part Number|IsMirrored=T
|RECORD=41|OwnerIndex=386|IndexInSheet=6|OwnerPartId=-1|Location.X=1112|Location.Y=195|Color=8388608|FontID=1|IsHidden=T|Name=Arrow Price/Stock|IsMirrored=T
|RECORD=14|OwnerIndex=386|IsNotAccesible=T|IndexInSheet=7|OwnerPartId=1|Location.X=1134|Location.Y=155|Corner.X=1194|Corner.Y=195|LineWidth=1|Color=128|AreaColor=11599871|IsSolid=T
|RECORD=2|OwnerIndex=386|OwnerPartId=1|FormalType=1|Electrical=7|PinConglomerate=56|PinLength=20|Location.X=1194|Location.Y=185|Name=ANODE|Designator=1|SwapIDPart=Ž&Ž||PinPropagationDelay=0.000000E+000
|RECORD=2|OwnerIndex=386|OwnerPartId=1|FormalType=1|Electrical=2|PinConglomerate=58|PinLength=20|Location.X=1134|Location.Y=165|Name=B|Designator=2|SwapIDPart=Ž&Ž||PinPropagationDelay=0.000000E+000
|RECORD=2|OwnerIndex=386|OwnerPartId=1|FormalType=1|Electrical=2|PinConglomerate=58|PinLength=20|Location.X=1134|Location.Y=175|Name=G|Designator=3|SwapIDPart=Ž&Ž||PinPropagationDelay=0.000000E+000
|RECORD=2|OwnerIndex=386|OwnerPartId=1|FormalType=1|Electrical=2|PinConglomerate=58|PinLength=20|Location.X=1134|Location.Y=185|Name=R|Designator=4|SwapIDPart=Ž&Ž||PinPropagationDelay=0.000000E+000
|RECORD=34|OwnerIndex=386|IndexInSheet=-1|OwnerPartId=-1|Location.X=1134|Location.Y=195|Color=8388608|FontID=1|Text=D18|Name=Designator|ReadOnlyState=1|IsMirrored=T
|RECORD=41|OwnerIndex=386|IndexInSheet=-1|OwnerPartId=-1|Location.X=1134|Location.Y=145|Color=8388608|FontID=1|Text=155124M173200|Name=Comment|IsMirrored=T
|RECORD=44|OwnerIndex=386
|RECORD=45|OwnerIndex=405|IndexInSheet=-1|ModelName=155124M173200|ModelType=PCBLIB|DatafileCount=1|ModelDatafile0=C:\Users\<user>\Documents\AltiumLL\SamacSys.PcbLib|ModelDatafileEntity0=155124M173200|ModelDatafileKind0=PCBLIB|IsCurrent=T
|RECORD=46|OwnerIndex=406
|RECORD=48|OwnerIndex=406
|RECORD=1|LibReference=IS32FL3207|PartCount=2|DisplayModeCount=1|IndexInSheet=20|OwnerPartId=-1|Location.X=644|Location.Y=455|CurrentPartId=1|LibraryPath=*|SourceLibraryName=IS32FL3207.SchLib|TargetFileName=*|AreaColor=11599871|Color=128|PartIDLocked=T|PinsMoveable=T|DesignItemId=IS32FL3207|AllPinCount=29
|RECORD=14|OwnerIndex=409|IsNotAccesible=T|OwnerPartId=1|Location.X=674|Location.Y=215|Corner.X=764|Corner.Y=455|Color=128|AreaColor=11599871|IsSolid=T
|RECORD=2|OwnerIndex=409|OwnerPartId=1|FormalType=1|PinConglomerate=26|PinLength=30|Location.X=674|Location.Y=385|Name=SDB|Designator=1|SwapIDPart=Ž&Ž||PinPropagationDelay=0.000000E+000
|RECORD=2|OwnerIndex=409|OwnerPartId=1|FormalType=1|PinConglomerate=26|PinLength=30|Location.X=674|Location.Y=415|Name=AD|Designator=2|SwapIDPart=Ž&Ž||PinPropagationDelay=0.000000E+000
|RECORD=2|OwnerIndex=409|OwnerPartId=1|FormalType=1|PinConglomerate=26|PinLength=30|Location.X=674|Location.Y=295|Name=VCC|Designator=3|SwapIDPart=Ž&Ž||PinPropagationDelay=0.000000E+000
|RECORD=2|OwnerIndex=409|OwnerPartId=1|FormalType=1|PinConglomerate=26|PinLength=30|Location.X=674|Location.Y=265|Name=GND|Designator=4|SwapIDPart=Ž&Ž||PinPropagationDelay=0.000000E+000
|RECORD=2|OwnerIndex=409|OwnerPartId=1|FormalType=1|PinConglomerate=26|PinLength=30|Location.X=674|Location.Y=365|Name=ISET|Designator=5|SwapIDPart=Ž&Ž||PinPropagationDelay=0.000000E+000
|RECORD=2|OwnerIndex=409|OwnerPartId=1|FormalType=1|PinConglomerate=26|PinLength=30|Location.X=674|Location.Y=445|Name=SDA|Designator=6|SwapIDPart=Ž&Ž||PinPropagationDelay=0.000000E+000
|RECORD=2|OwnerIndex=409|OwnerPartId=1|FormalType=1|PinConglomerate=26|PinLength=30|Location.X=674|Location.Y=435|Name=SCL|Designator=7|SwapIDPart=Ž&Ž||PinPropagationDelay=0.000000E+000
|RECORD=2|OwnerIndex=409|OwnerPartId=1|FormalType=1|PinConglomerate=24|PinLength=30|Location.X=764|Location.Y=445|Name=OUT1|Designator=8|SwapIDPart=Ž&Ž||PinPropagationDelay=0.000000E+000
|RECORD=2|OwnerIndex=409|OwnerPartId=1|FormalType=1|PinConglomerate=24|PinLength=30|Location.X=764|Location.Y=435|Name=OUT2|Designator=9|SwapIDPart=Ž&Ž||PinPropagationDelay=0.000000E+000
|RECORD=2|OwnerIndex=409|OwnerPartId=1|FormalType=1|PinConglomerate=24|PinLength=30|Location.X=764|Location.Y=425|Name=OUT3|Designator=10|SwapIDPart=Ž&Ž||PinPropagationDelay=0.000000E+000
|RECORD=2|OwnerIndex=409|OwnerPartId=1|FormalType=1|PinConglomerate=26|PinLength=30|Location.X=674|Location.Y=255|Name=GND|Designator=11|SwapIDPart=Ž&Ž||PinPropagationDelay=0.000000E+000
|RECORD=2|OwnerIndex=409|OwnerPartId=1|FormalType=1|PinConglomerate=24|PinLength=30|Location.X=764|Location.Y=405|Name=OUT4|Designator=12|SwapIDPart=Ž&Ž||PinPropagationDelay=0.000000E+000
|RECORD=2|OwnerIndex=409|OwnerPartId=1|FormalType=1|PinConglomerate=24|PinLength=30|Location.X=764|Location.Y=395|Name=OUT5|Designator=13|SwapIDPart=Ž&Ž||PinPropagationDelay=0.000000E+000
|RECORD=2|OwnerIndex=409|OwnerPartId=1|FormalType=1|PinConglomerate=24|PinLength=30|Location.X=764|Location.Y=385|Name=OUT6|Designator=14|SwapIDPart=Ž&Ž||PinPropagationDelay=0.000000E+000
|RECORD=2|OwnerIndex=409|OwnerPartId=1|FormalType=1|PinConglomerate=24|PinLength=30|Location.X=764|Location.Y=365|Name=OUT7|Designator=15|SwapIDPart=Ž&Ž||PinPropagationDelay=0.000000E+000
|RECORD=2|OwnerIndex=409|OwnerPartId=1|FormalType=1|PinConglomerate=24|PinLength=30|Location.X=764|Location.Y=355|Name=OUT8|Designator=16|SwapIDPart=Ž&Ž||PinPropagationDelay=0.000000E+000
|RECORD=2|OwnerIndex=409|OwnerPartId=1|FormalType=1|PinConglomerate=24|PinLength=30|Location.X=764|Location.Y=345|Name=OUT9|Designator=17|SwapIDPart=Ž&Ž||PinPropagationDelay=0.000000E+000
|RECORD=2|OwnerIndex=409|OwnerPartId=1|FormalType=1|PinConglomerate=26|PinLength=30|Location.X=674|Location.Y=245|Name=GND|Designator=18|SwapIDPart=Ž&Ž||PinPropagationDelay=0.000000E+000
|RECORD=2|OwnerIndex=409|OwnerPartId=1|FormalType=1|PinConglomerate=24|PinLength=30|Location.X=764|Location.Y=325|Name=OUT10|Designator=19|SwapIDPart=Ž&Ž||PinPropagationDelay=0.000000E+000
|RECORD=2|OwnerIndex=409|OwnerPartId=1|FormalType=1|PinConglomerate=24|PinLength=30|Location.X=764|Location.Y=315|Name=OUT11|Designator=20|SwapIDPart=Ž&Ž||PinPropagationDelay=0.000000E+000
|RECORD=2|OwnerIndex=409|OwnerPartId=1|FormalType=1|PinConglomerate=24|PinLength=30|Location.X=764|Location.Y=305|Name=OUT12|Designator=21|SwapIDPart=Ž&Ž||PinPropagationDelay=0.000000E+000
|RECORD=2|OwnerIndex=409|OwnerPartId=1|FormalType=1|PinConglomerate=24|PinLength=30|Location.X=764|Location.Y=285|Name=OUT13|Designator=22|SwapIDPart=Ž&Ž||PinPropagationDelay=0.000000E+000
|RECORD=2|OwnerIndex=409|OwnerPartId=1|FormalType=1|PinConglomerate=24|PinLength=30|Location.X=764|Location.Y=275|Name=OUT14|Designator=23|SwapIDPart=Ž&Ž||PinPropagationDelay=0.000000E+000
|RECORD=2|OwnerIndex=409|OwnerPartId=1|FormalType=1|PinConglomerate=24|PinLength=30|Location.X=764|Location.Y=265|Name=OUT15|Designator=24|SwapIDPart=Ž&Ž||PinPropagationDelay=0.000000E+000
|RECORD=2|OwnerIndex=409|OwnerPartId=1|FormalType=1|PinConglomerate=26|PinLength=30|Location.X=674|Location.Y=235|Name=GND|Designator=25|SwapIDPart=Ž&Ž||PinPropagationDelay=0.000000E+000
|RECORD=2|OwnerIndex=409|OwnerPartId=1|FormalType=1|PinConglomerate=24|PinLength=30|Location.X=764|Location.Y=245|Name=OUT16|Designator=26|SwapIDPart=Ž&Ž||PinPropagationDelay=0.000000E+000
|RECORD=2|OwnerIndex=409|OwnerPartId=1|FormalType=1|PinConglomerate=24|PinLength=30|Location.X=764|Location.Y=235|Name=OUT17|Designator=27|SwapIDPart=Ž&Ž||PinPropagationDelay=0.000000E+000
|RECORD=2|OwnerIndex=409|OwnerPartId=1|FormalType=1|PinConglomerate=24|PinLength=30|Location.X=764|Location.Y=225|Name=OUT18|Designator=28|SwapIDPart=Ž&Ž||PinPropagationDelay=0.000000E+000
|RECORD=2|OwnerIndex=409|OwnerPartId=1|FormalType=1|PinConglomerate=26|PinLength=30|Location.X=674|Location.Y=225|Name=EP|Designator=29|SwapIDPart=Ž&Ž||PinPropagationDelay=0.000000E+000
|RECORD=34|OwnerIndex=409|IndexInSheet=-1|OwnerPartId=-1|Location.X=674|Location.Y=455|Color=8388608|FontID=1|Text=U6|Name=Designator|ReadOnlyState=1
|RECORD=41|OwnerIndex=409|IndexInSheet=-1|OwnerPartId=-1|Location.X=674|Location.Y=205|Color=8388608|FontID=1|Text=IS32FL3207|Name=Comment
|RECORD=44|OwnerIndex=409
|RECORD=45|OwnerIndex=471|IndexInSheet=-1|ModelName=IS32FL3207|ModelType=PCBLIB|DatafileCount=1|ModelDatafileEntity0=IS32FL3207|ModelDatafileKind0=PCBLib|IsCurrent=T
|RECORD=46|OwnerIndex=472
|RECORD=48|OwnerIndex=472
|RECORD=17|IndexInSheet=21|OwnerPartId=-1|ShowNetName=T|Location.X=1244|Location.Y=555|Orientation=1|Color=128|FontID=1|Text=+3.3V
|RECORD=4|IndexInSheet=22|OwnerPartId=-1|Location.X=734|Location.Y=575|Color=8388608|FontID=6|Text=IO STATUS LEDS
|RECORD=4|IndexInSheet=23|OwnerPartId=-1|Location.X=1264|Location.Y=485|Color=8388608|FontID=6|Text=GNSS 1
|RECORD=4|IndexInSheet=24|OwnerPartId=-1|Location.X=1264|Location.Y=425|Color=8388608|FontID=6|Text=GNSS 2
|RECORD=4|IndexInSheet=25|OwnerPartId=-1|Location.X=1264|Location.Y=365|Color=8388608|FontID=6|Text=IO 1
|RECORD=4|IndexInSheet=26|OwnerPartId=-1|Location.X=1264|Location.Y=305|Color=8388608|FontID=6|Text=IO 2
|RECORD=4|IndexInSheet=27|OwnerPartId=-1|Location.X=1264|Location.Y=235|Color=8388608|FontID=6|Text=IO 3
|RECORD=4|IndexInSheet=28|OwnerPartId=-1|Location.X=1264|Location.Y=165|Color=8388608|FontID=6|Text=IO 4
|RECORD=1|LibReference=CAP|ComponentDescription=C0603X104K5RACAUTO|PartCount=2|DisplayModeCount=2|IndexInSheet=29|OwnerPartId=-1|Location.X=524|Location.Y=185|Orientation=1|CurrentPartId=1|SourceLibraryName=Altium Content Vault|TargetFileName=*|AreaColor=11599871|Color=128|PartIDLocked=F|DesignItemId=CMP-2006-00003-1|AllPinCount=2
|RECORD=2|OwnerIndex=483|OwnerPartId=1|OwnerPartDisplayMode=1|FormalType=1|Electrical=4|PinConglomerate=35|PinLength=10|Location.X=534|Location.Y=185|Name=1|Designator=1|PinPropagationDelay=0.000000E+000
|RECORD=2|OwnerIndex=483|OwnerPartId=1|OwnerPartDisplayMode=1|FormalType=1|Electrical=4|PinConglomerate=33|PinLength=10|Location.X=534|Location.Y=195|Name=2|Designator=2|PinPropagationDelay=0.000000E+000
|RECORD=13|OwnerIndex=483|IsNotAccesible=T|IndexInSheet=2|OwnerPartId=1|OwnerPartDisplayMode=1|Location.X=542|Location.Y=185|Corner.X=526|Corner.Y=185|LineWidth=1|Color=16711680
|RECORD=13|OwnerIndex=483|IsNotAccesible=T|IndexInSheet=3|OwnerPartId=1|OwnerPartDisplayMode=1|Location.X=534|Location.Y=189|Corner.X=534|Corner.Y=195|LineWidth=1|Color=16711680
|RECORD=12|OwnerIndex=483|IsNotAccesible=T|IndexInSheet=4|OwnerPartId=1|OwnerPartDisplayMode=1|Location.X=534|Location.Y=205|Radius=16|LineWidth=1|StartAngle=241.000|EndAngle=270.000|Color=16711680
|RECORD=12|OwnerIndex=483|IsNotAccesible=T|IndexInSheet=5|OwnerPartId=1|OwnerPartDisplayMode=1|Location.X=534|Location.Y=205|Radius=16|LineWidth=1|StartAngle=270.000|EndAngle=299.000|Color=16711680
|RECORD=2|OwnerIndex=483|OwnerPartId=1|FormalType=1|Electrical=4|PinConglomerate=35|PinLength=10|Location.X=534|Location.Y=185|Name=1|Designator=1|PinPropagationDelay=0.000000E+000
|RECORD=2|OwnerIndex=483|OwnerPartId=1|FormalType=1|Electrical=4|PinConglomerate=33|PinLength=10|Location.X=534|Location.Y=195|Name=2|Designator=2|PinPropagationDelay=0.000000E+000
|RECORD=13|OwnerIndex=483|IsNotAccesible=T|IndexInSheet=8|OwnerPartId=1|Location.X=526|Location.Y=192|Corner.X=542|Corner.Y=192|LineWidth=1|Color=16711680
|RECORD=13|OwnerIndex=483|IsNotAccesible=T|IndexInSheet=9|OwnerPartId=1|Location.X=542|Location.Y=188|Corner.X=526|Corner.Y=188|LineWidth=1|Color=16711680
|RECORD=6|OwnerIndex=483|IsNotAccesible=T|IndexInSheet=10|OwnerPartId=1|LineWidth=1|Color=16711680|LocationCount=2|X1=534|Y1=185|X2=534|Y2=188
|RECORD=6|OwnerIndex=483|IsNotAccesible=T|IndexInSheet=11|OwnerPartId=1|LineWidth=1|Color=16711680|LocationCount=2|X1=534|Y1=195|X2=534|Y2=192
|RECORD=41|OwnerIndex=483|IndexInSheet=12|OwnerPartId=-1|Location.X=525|Location.Y=207|Color=8388608|FontID=1|IsHidden=T|Text=Kemet|Name=Manufacturer
|RECORD=41|OwnerIndex=483|IndexInSheet=13|OwnerPartId=-1|Location.X=525|Location.Y=207|Color=8388608|FontID=1|IsHidden=T|Text=C0603X104K5RACAUTO|Name=Part Number
|RECORD=34|OwnerIndex=483|IndexInSheet=-1|OwnerPartId=-1|Location.X=543|Location.Y=186|Color=8388608|FontID=1|Text=C40|Name=Designator|ReadOnlyState=1
|RECORD=41|OwnerIndex=483|IndexInSheet=-1|OwnerPartId=-1|Location.X=543|Location.Y=176|Color=8388608|FontID=1|Text=0.1uF|Name=Comment
|RECORD=44|OwnerIndex=483
|RECORD=45|OwnerIndex=504|IndexInSheet=-1|Description=Chip Capacitor, 2-Leads, Body 1.60x0.80mm, IPC Low Density|UseComponentLibrary=T|ModelName=CAPC1608X87X45ML20T05|ModelType=PCBLIB|DatafileCount=1|ModelDatafileEntity0=CAPC1608X87X45ML20T05|ModelDatafileKind0=PCBLib|IsCurrent=T|DatalinksLocked=T|DatabaseDatalinksLocked=T
|RECORD=46|OwnerIndex=505
|RECORD=48|OwnerIndex=505
|RECORD=41|OwnerIndex=507|IndexInSheet=-1|OwnerPartId=-1|Color=8388608|FontID=1|Text=2D|Name=Available Preview Images
|RECORD=45|OwnerIndex=504|IndexInSheet=-1|Description=Chip Capacitor, 2-Leads, Body 1.60x0.80mm, IPC High Density|UseComponentLibrary=T|ModelName=CAPC1608X87X45LL20T05|ModelType=PCBLIB|DatafileCount=1|ModelDatafileEntity0=CAPC1608X87X45LL20T05|ModelDatafileKind0=PCBLib|DatalinksLocked=T|DatabaseDatalinksLocked=T
|RECORD=46|OwnerIndex=509
|RECORD=48|OwnerIndex=509
|RECORD=41|OwnerIndex=511|IndexInSheet=-1|OwnerPartId=-1|Color=8388608|FontID=1|Text=2D|Name=Available Preview Images
|RECORD=45|OwnerIndex=504|IndexInSheet=-1|Description=Chip Capacitor, 2-Leads, Body 1.60x0.80mm, IPC Medium Density|UseComponentLibrary=T|ModelName=CAPC1608X87X45NL20T05|ModelType=PCBLIB|DatafileCount=1|ModelDatafileEntity0=CAPC1608X87X45NL20T05|ModelDatafileKind0=PCBLib|DatalinksLocked=T|DatabaseDatalinksLocked=T
|RECORD=46|OwnerIndex=513
|RECORD=48|OwnerIndex=513
|RECORD=41|OwnerIndex=515|IndexInSheet=-1|OwnerPartId=-1|Color=8388608|FontID=1|Text=2D|Name=Available Preview Images
|RECORD=1|LibReference=e9c51b7dd13d4faca003ae77663ab08|ComponentDescription=CAP CER 1UF 25V X5R 0603|PartCount=2|DisplayModeCount=1|IndexInSheet=30|OwnerPartId=-1|Location.X=444|Location.Y=205|CurrentPartId=1|LibraryPath=*|SourceLibraryName=Altium Content Vault|TargetFileName=*|AreaColor=11599871|Color=128|PartIDLocked=T|DesignItemId=CMP-2006-02216-3|AllPinCount=2
|RECORD=2|OwnerIndex=517|OwnerPartId=1|Electrical=4|PinConglomerate=33|PinLength=7|Location.X=444|Location.Y=198|Name=1|Designator=1|PinName_PositionConglomerate=16|Name_CustomFontID=1|PinDesignator_PositionConglomerate=16|Designator_CustomFontID=1|PinPropagationDelay=0.000000E+000
|RECORD=2|OwnerIndex=517|OwnerPartId=1|Electrical=4|PinConglomerate=35|PinLength=6|Location.X=444|Location.Y=191|Name=2|Designator=2|PinName_PositionConglomerate=16|Name_CustomFontID=1|PinDesignator_PositionConglomerate=16|Designator_CustomFontID=1|PinPropagationDelay=0.000000E+000
|RECORD=13|OwnerIndex=517|IsNotAccesible=T|IndexInSheet=2|OwnerPartId=1|Location.X=454|Location.Y=198|Corner.X=434|Corner.Y=198|LineWidth=1|Color=16711680
|RECORD=13|OwnerIndex=517|IsNotAccesible=T|IndexInSheet=3|OwnerPartId=1|Location.X=454|Location.Y=192|Corner.X=434|Corner.Y=192|LineWidth=1|Color=16711680
|RECORD=13|OwnerIndex=517|IsNotAccesible=T|IndexInSheet=4|OwnerPartId=1|Location.X=444|Location.Y=198|Corner.X=444|Corner.Y=201|LineWidth=1|Color=16711680
|RECORD=13|OwnerIndex=517|IsNotAccesible=T|IndexInSheet=5|OwnerPartId=1|Location.X=444|Location.Y=191|Corner.X=444|Corner.Y=190|LineWidth=1|Color=16711680
|RECORD=41|OwnerIndex=517|IndexInSheet=6|OwnerPartId=-1|Location.X=433|Location.Y=207|Color=8388608|FontID=1|IsHidden=T|Text=Tin|Name=Contact Plating
|RECORD=41|OwnerIndex=517|IndexInSheet=7|OwnerPartId=-1|Location.X=433|Location.Y=207|Color=8388608|FontID=1|IsHidden=T|Text=2|Name=Number of Pins
|RECORD=41|OwnerIndex=517|IndexInSheet=8|OwnerPartId=-1|Location.X=433|Location.Y=207|Color=8388608|FontID=1|IsHidden=T|Text=Lead Free|Name=Lead Free
|RECORD=41|OwnerIndex=517|IndexInSheet=9|OwnerPartId=-1|Location.X=433|Location.Y=207|Color=8388608|FontID=1|IsHidden=T|Text=0.8mm|Name=Depth
|RECORD=41|OwnerIndex=517|IndexInSheet=10|OwnerPartId=-1|Location.X=433|Location.Y=207|Color=8388608|FontID=1|IsHidden=T|Text=1.6mm|Name=Length
|RECORD=41|OwnerIndex=517|IndexInSheet=11|OwnerPartId=-1|Location.X=433|Location.Y=207|Color=8388608|FontID=1|IsHidden=T|Text=Surface Mount|Name=Mount
|RECORD=41|OwnerIndex=517|IndexInSheet=12|OwnerPartId=-1|Location.X=433|Location.Y=207|Color=8388608|FontID=1|IsHidden=T|Text=1608|Name=Case Code (Metric)
|RECORD=41|OwnerIndex=517|IndexInSheet=13|OwnerPartId=-1|Location.X=433|Location.Y=207|Color=8388608|FontID=1|IsHidden=T|Text=85°C|Name=Max Operating Temperature
|RECORD=41|OwnerIndex=517|IndexInSheet=14|OwnerPartId=-1|Location.X=433|Location.Y=207|Color=8388608|FontID=1|IsHidden=T|Text=25V|Name=Voltage
|RECORD=41|OwnerIndex=517|IndexInSheet=15|OwnerPartId=-1|Location.X=433|Location.Y=207|Color=8388608|FontID=1|IsHidden=T|Text=25V|Name=Voltage Rating (DC)
|RECORD=41|OwnerIndex=517|IndexInSheet=16|OwnerPartId=-1|Location.X=433|Location.Y=207|Color=8388608|FontID=1|IsHidden=T|Text=Ceramic|Name=Dielectric Material
|RECORD=41|OwnerIndex=517|IndexInSheet=17|OwnerPartId=-1|Location.X=433|Location.Y=207|Color=8388608|FontID=1|IsHidden=T|Text=No SVHC|Name=REACH SVHC
|RECORD=41|OwnerIndex=517|IndexInSheet=18|OwnerPartId=-1|Location.X=433|Location.Y=207|Color=8388608|FontID=1|IsHidden=T|Text=0.8mm|Name=Height
|RECORD=41|OwnerIndex=517|IndexInSheet=19|OwnerPartId=-1|Location.X=433|Location.Y=207|Color=8388608|FontID=1|IsHidden=T|Text=C0603C|Name=Series
|RECORD=41|OwnerIndex=517|IndexInSheet=20|OwnerPartId=-1|Location.X=433|Location.Y=207|Color=8388608|FontID=1|IsHidden=T|Text=0603|Name=Case/Package
|RECORD=41|OwnerIndex=517|IndexInSheet=21|OwnerPartId=-1|Location.X=433|Location.Y=207|Color=8388608|FontID=1|IsHidden=T|Text=0603|Name=Case Code (Imperial)
|RECORD=41|OwnerIndex=517|IndexInSheet=22|OwnerPartId=-1|Location.X=433|Location.Y=207|Color=8388608|FontID=1|IsHidden=T|Text=1uF|Name=Capacitance
|RECORD=41|OwnerIndex=517|IndexInSheet=23|OwnerPartId=-1|Location.X=433|Location.Y=207|Color=8388608|FontID=1|IsHidden=T|Text=Yes|Name=RoHS Compliant
|RECORD=41|OwnerIndex=517|IndexInSheet=24|OwnerPartId=-1|Location.X=433|Location.Y=207|Color=8388608|FontID=1|IsHidden=T|Text=X5R|Name=Dielectric
|RECORD=41|OwnerIndex=517|IndexInSheet=25|OwnerPartId=-1|Location.X=433|Location.Y=207|Color=8388608|FontID=1|IsHidden=T|Text=Tape and Reel|Name=Packaging
|RECORD=41|OwnerIndex=517|IndexInSheet=26|OwnerPartId=-1|Location.X=433|Location.Y=207|Color=8388608|FontID=1|IsHidden=T|Text=Flat|Name=Construction
|RECORD=41|OwnerIndex=517|IndexInSheet=27|OwnerPartId=-1|Location.X=433|Location.Y=207|Color=8388608|FontID=1|IsHidden=T|Text=0.034inch|Name=Thickness
|RECORD=41|OwnerIndex=517|IndexInSheet=28|OwnerPartId=-1|Location.X=433|Location.Y=207|Color=8388608|FontID=1|IsHidden=T|Text=25V|Name=Voltage Rating
|RECORD=41|OwnerIndex=517|IndexInSheet=29|OwnerPartId=-1|Location.X=433|Location.Y=207|Color=8388608|FontID=1|IsHidden=T|Text=No|Name=Radiation Hardening
|RECORD=41|OwnerIndex=517|IndexInSheet=30|OwnerPartId=-1|Location.X=433|Location.Y=207|Color=8388608|FontID=1|IsHidden=T|Text=0.031inch|Name=Width
|RECORD=41|OwnerIndex=517|IndexInSheet=31|OwnerPartId=-1|Location.X=433|Location.Y=207|Color=8388608|FontID=1|IsHidden=T|Text=-55°C|Name=Min Operating Temperature
|RECORD=41|OwnerIndex=517|IndexInSheet=32|OwnerPartId=-1|Location.X=433|Location.Y=207|Color=8388608|FontID=1|IsHidden=T|Text=SMD/SMT|Name=Termination
|RECORD=41|OwnerIndex=517|IndexInSheet=33|OwnerPartId=-1|Location.X=433|Location.Y=207|Color=8388608|FontID=1|IsHidden=T|Text=10%|Name=Tolerance
|RECORD=41|OwnerIndex=517|IndexInSheet=34|OwnerPartId=-1|Location.X=433|Location.Y=207|Color=8388608|FontID=1|IsHidden=T|Text=4000|Name=Package Quantity
|RECORD=34|OwnerIndex=517|IndexInSheet=-1|OwnerPartId=-1|Location.X=455|Location.Y=192|Color=8388608|FontID=1|Text=C38|Name=Designator|ReadOnlyState=1
|RECORD=41|OwnerIndex=517|IndexInSheet=-1|OwnerPartId=1|Location.X=455|Location.Y=182|Color=8388608|FontID=1|Text=1uF|Name=Comment
|RECORD=44|OwnerIndex=517
|RECORD=45|OwnerIndex=557|IndexInSheet=-1|UseComponentLibrary=T|ModelName=FP-C0603C105K3PACTU-MFG|ModelType=PCBLIB|DatafileCount=1|ModelDatafileEntity0=FP-C0603C105K3PACTU-MFG|ModelDatafileKind0=PCBLib|IsCurrent=T|DatalinksLocked=T|DatabaseDatalinksLocked=T
|RECORD=46|OwnerIndex=558
|RECORD=48|OwnerIndex=558
|RECORD=45|OwnerIndex=557|IndexInSheet=-1|UseComponentLibrary=T|ModelName=FP-C0603C105K3PACTU-IPC_C|ModelType=PCBLIB|DatafileCount=1|ModelDatafileEntity0=FP-C0603C105K3PACTU-IPC_C|ModelDatafileKind0=PCBLib|DatalinksLocked=T|DatabaseDatalinksLocked=T
|RECORD=46|OwnerIndex=561
|RECORD=48|OwnerIndex=561
|RECORD=45|OwnerIndex=557|IndexInSheet=-1|UseComponentLibrary=T|ModelName=FP-C0603C105K3PACTU-IPC_B|ModelType=PCBLIB|DatafileCount=1|ModelDatafileEntity0=FP-C0603C105K3PACTU-IPC_B|ModelDatafileKind0=PCBLib|DatalinksLocked=T|DatabaseDatalinksLocked=T
|RECORD=46|OwnerIndex=564
|RECORD=48|OwnerIndex=564
|RECORD=45|OwnerIndex=557|IndexInSheet=-1|UseComponentLibrary=T|ModelName=FP-C0603C105K3PACTU-IPC_A|ModelType=PCBLIB|DatafileCount=1|ModelDatafileEntity0=FP-C0603C105K3PACTU-IPC_A|ModelDatafileKind0=PCBLib|DatalinksLocked=T|DatabaseDatalinksLocked=T
|RECORD=46|OwnerIndex=567
|RECORD=48|OwnerIndex=567
|RECORD=1|LibReference=1029c3af85768c4190bb7ad29bc67b5|ComponentDescription=RES SMD 100K OHM 1% 1/10W 0603|PartCount=2|DisplayModeCount=1|IndexInSheet=31|OwnerPartId=-1|Location.X=364|Location.Y=165|Orientation=1|CurrentPartId=1|LibraryPath=*|SourceLibraryName=Altium Content Vault|TargetFileName=*|AreaColor=11599871|Color=128|PartIDLocked=T|DesignItemId=CMP-2100-03662-2|AllPinCount=2|ComponentKindVersion2=5
|RECORD=2|OwnerIndex=570|OwnerPartId=1|Electrical=4|PinConglomerate=35|PinLength=20|Location.X=364|Location.Y=185|Name=1|Designator=1|PinPropagationDelay=0.000000E+000
|RECORD=2|OwnerIndex=570|OwnerPartId=1|Electrical=4|PinConglomerate=33|PinLength=20|Location.X=364|Location.Y=215|Name=2|Designator=2|PinPropagationDelay=0.000000E+000
|RECORD=13|OwnerIndex=570|IsNotAccesible=T|IndexInSheet=2|OwnerPartId=1|Location.X=364|Location.Y=185|Corner.X=359|Corner.Y=188|LineWidth=1|Color=16711680
|RECORD=13|OwnerIndex=570|IsNotAccesible=T|IndexInSheet=3|OwnerPartId=1|Location.X=359|Location.Y=188|Corner.X=369|Corner.Y=193|LineWidth=1|Color=16711680
|RECORD=13|OwnerIndex=570|IsNotAccesible=T|IndexInSheet=4|OwnerPartId=1|Location.X=369|Location.Y=193|Corner.X=359|Corner.Y=198|LineWidth=1|Color=16711680
|RECORD=13|OwnerIndex=570|IsNotAccesible=T|IndexInSheet=5|OwnerPartId=1|Location.X=359|Location.Y=198|Corner.X=369|Corner.Y=203|LineWidth=1|Color=16711680
|RECORD=13|OwnerIndex=570|IsNotAccesible=T|IndexInSheet=6|OwnerPartId=1|Location.X=369|Location.Y=203|Corner.X=359|Corner.Y=208|LineWidth=1|Color=16711680
|RECORD=13|OwnerIndex=570|IsNotAccesible=T|IndexInSheet=7|OwnerPartId=1|Location.X=359|Location.Y=208|Corner.X=369|Corner.Y=213|LineWidth=1|Color=16711680
|RECORD=13|OwnerIndex=570|IsNotAccesible=T|IndexInSheet=8|OwnerPartId=1|Location.X=369|Location.Y=213|Corner.X=364|Corner.Y=215|LineWidth=1|Color=16711680
|RECORD=13|OwnerIndex=570|IsNotAccesible=T|IndexInSheet=9|OwnerPartId=1|Location.X=364|Location.Y=185|Corner.X=364|Corner.Y=182|LineWidth=1|Color=16711680
|RECORD=13|OwnerIndex=570|IsNotAccesible=T|IndexInSheet=10|OwnerPartId=1|Location.X=364|Location.Y=215|Corner.X=364|Corner.Y=218|LineWidth=1|Color=16711680
|RECORD=41|OwnerIndex=570|IndexInSheet=11|OwnerPartId=-1|Location.X=358|Location.Y=237|Color=8388608|FontID=1|IsHidden=T|Text=1.6mm|Name=Length
|RECORD=41|OwnerIndex=570|IndexInSheet=12|OwnerPartId=-1|Location.X=358|Location.Y=237|Color=8388608|FontID=1|IsHidden=T|Text=Lead Free|Name=Lead Free
|RECORD=41|OwnerIndex=570|IndexInSheet=13|OwnerPartId=-1|Location.X=358|Location.Y=237|Color=8388608|FontID=1|IsHidden=T|Text=2|Name=Number of Terminations
|RECORD=41|OwnerIndex=570|IndexInSheet=14|OwnerPartId=-1|Location.X=358|Location.Y=237|Color=8388608|FontID=1|IsHidden=T|Text=50V|Name=Voltage Rating (DC)
|RECORD=41|OwnerIndex=570|IndexInSheet=15|OwnerPartId=-1|Location.X=358|Location.Y=237|Color=8388608|FontID=1|IsHidden=T|Text=Tape and Reel|Name=Packaging
|RECORD=41|OwnerIndex=570|IndexInSheet=16|OwnerPartId=-1|Location.X=358|Location.Y=237|Color=8388608|FontID=1|IsHidden=T|Text=50V|Name=Voltage Rating
|RECORD=41|OwnerIndex=570|IndexInSheet=17|OwnerPartId=-1|Location.X=358|Location.Y=237|Color=8388608|FontID=1|IsHidden=T|Text=SMD/SMT|Name=Termination
|RECORD=41|OwnerIndex=570|IndexInSheet=18|OwnerPartId=-1|Location.X=358|Location.Y=237|Color=8388608|FontID=1|IsHidden=T|Text=0.8mm|Name=Width
|RECORD=41|OwnerIndex=570|IndexInSheet=19|OwnerPartId=-1|Location.X=358|Location.Y=237|Color=8388608|FontID=1|IsHidden=T|Text=100kR|Name=Resistance
|RECORD=41|OwnerIndex=570|IndexInSheet=20|OwnerPartId=-1|Location.X=358|Location.Y=237|Color=8388608|FontID=1|IsHidden=T|Text=Thick Film|Name=Resistor Type
|RECORD=41|OwnerIndex=570|IndexInSheet=21|OwnerPartId=-1|Location.X=358|Location.Y=237|Color=8388608|FontID=1|IsHidden=T|Text=100mW|Name=Max Power Dissipation
|RECORD=41|OwnerIndex=570|IndexInSheet=22|OwnerPartId=-1|Location.X=358|Location.Y=237|Color=8388608|FontID=1|IsHidden=T|Text=1%|Name=Resistance Tolerance
|RECORD=41|OwnerIndex=570|IndexInSheet=23|OwnerPartId=-1|Location.X=358|Location.Y=237|Color=8388608|FontID=1|IsHidden=T|Text=Moisture Resistant|Name=Features
|RECORD=41|OwnerIndex=570|IndexInSheet=24|OwnerPartId=-1|Location.X=358|Location.Y=237|Color=8388608|FontID=1|IsHidden=T|Text=0.45mm|Name=Height
|RECORD=41|OwnerIndex=570|IndexInSheet=25|OwnerPartId=-1|Location.X=358|Location.Y=237|Color=8388608|FontID=1|IsHidden=T|Text=Rectangular|Name=Construction
|RECORD=41|OwnerIndex=570|IndexInSheet=26|OwnerPartId=-1|Location.X=358|Location.Y=237|Color=8388608|FontID=1|IsHidden=T|Text=0603|Name=Case/Package
|RECORD=41|OwnerIndex=570|IndexInSheet=27|OwnerPartId=-1|Location.X=358|Location.Y=237|Color=8388608|FontID=1|IsHidden=T|Text=Not|Name=Military Standard
|RECORD=41|OwnerIndex=570|IndexInSheet=28|OwnerPartId=-1|Location.X=358|Location.Y=237|Color=8388608|FontID=1|IsHidden=T|Text=0603|Name=Case Code (Imperial)
|RECORD=41|OwnerIndex=570|IndexInSheet=29|OwnerPartId=-1|Location.X=358|Location.Y=237|Color=8388608|FontID=1|IsHidden=T|Text=100ppm/°C|Name=Temperature Coefficient
|RECORD=41|OwnerIndex=570|IndexInSheet=30|OwnerPartId=-1|Location.X=358|Location.Y=237|Color=8388608|FontID=1|IsHidden=T|Text=RC|Name=Series
|RECORD=41|OwnerIndex=570|IndexInSheet=31|OwnerPartId=-1|Location.X=358|Location.Y=237|Color=8388608|FontID=1|IsHidden=T|Text=THICK FILM|Name=Technology
|RECORD=41|OwnerIndex=570|IndexInSheet=32|OwnerPartId=-1|Location.X=358|Location.Y=237|Color=8388608|FontID=1|IsHidden=T|Text=0.8mm|Name=Depth
|RECORD=41|OwnerIndex=570|IndexInSheet=33|OwnerPartId=-1|Location.X=358|Location.Y=237|Color=8388608|FontID=1|IsHidden=T|Text=Yes|Name=RoHS Compliant
|RECORD=41|OwnerIndex=570|IndexInSheet=34|OwnerPartId=-1|Location.X=358|Location.Y=237|Color=8388608|FontID=1|IsHidden=T|Text=75V|Name=Working Voltage
|RECORD=41|OwnerIndex=570|IndexInSheet=35|OwnerPartId=-1|Location.X=358|Location.Y=237|Color=8388608|FontID=1|IsHidden=T|Text=No SVHC|Name=REACH SVHC
|RECORD=41|OwnerIndex=570|IndexInSheet=36|OwnerPartId=-1|Location.X=358|Location.Y=237|Color=8388608|FontID=1|IsHidden=T|Text=-55°C|Name=Min Operating Temperature
|RECORD=41|OwnerIndex=570|IndexInSheet=37|OwnerPartId=-1|Location.X=358|Location.Y=237|Color=8388608|FontID=1|IsHidden=T|Text=1608|Name=Case Code (Metric)
|RECORD=41|OwnerIndex=570|IndexInSheet=38|OwnerPartId=-1|Location.X=358|Location.Y=237|Color=8388608|FontID=1|IsHidden=T|Text=155°C|Name=Max Operating Temperature
|RECORD=41|OwnerIndex=570|IndexInSheet=39|OwnerPartId=-1|Location.X=358|Location.Y=237|Color=8388608|FontID=1|IsHidden=T|Text=100mW|Name=Power Rating
|RECORD=41|OwnerIndex=570|IndexInSheet=40|OwnerPartId=-1|Location.X=358|Location.Y=237|Color=8388608|FontID=1|IsHidden=T|Text=2|Name=Number of Pins
|RECORD=41|OwnerIndex=570|IndexInSheet=41|OwnerPartId=-1|Location.X=358|Location.Y=237|Color=8388608|FontID=1|IsHidden=T|Text=1%|Name=Tolerance
|RECORD=34|OwnerIndex=570|IndexInSheet=-1|OwnerPartId=-1|Location.X=370|Location.Y=209|Color=8388608|FontID=1|Text=R40|Name=Designator|ReadOnlyState=1
|RECORD=41|OwnerIndex=570|IndexInSheet=-1|OwnerPartId=1|Location.X=370|Location.Y=199|Color=8388608|FontID=1|Text=DNI_100k|Name=Comment
|RECORD=44|OwnerIndex=570
|RECORD=45|OwnerIndex=617|IndexInSheet=-1|UseComponentLibrary=T|ModelName=FP-RC0603-0_55-MFG|ModelType=PCBLIB|DatafileCount=1|ModelDatafileEntity0=FP-RC0603-0_55-MFG|ModelDatafileKind0=PCBLib|IsCurrent=T|DatalinksLocked=T|DatabaseDatalinksLocked=T
|RECORD=46|OwnerIndex=618
|RECORD=48|OwnerIndex=618
|RECORD=45|OwnerIndex=617|IndexInSheet=-1|UseComponentLibrary=T|ModelName=FP-RC0603-0_55-IPC_C|ModelType=PCBLIB|DatafileCount=1|ModelDatafileEntity0=FP-RC0603-0_55-IPC_C|ModelDatafileKind0=PCBLib|DatalinksLocked=T|DatabaseDatalinksLocked=T
|RECORD=46|OwnerIndex=621
|RECORD=48|OwnerIndex=621
|RECORD=45|OwnerIndex=617|IndexInSheet=-1|UseComponentLibrary=T|ModelName=FP-RC0603-0_55-IPC_B|ModelType=PCBLIB|DatafileCount=1|ModelDatafileEntity0=FP-RC0603-0_55-IPC_B|ModelDatafileKind0=PCBLib|DatalinksLocked=T|DatabaseDatalinksLocked=T
|RECORD=46|OwnerIndex=624
|RECORD=48|OwnerIndex=624
|RECORD=45|OwnerIndex=617|IndexInSheet=-1|UseComponentLibrary=T|ModelName=FP-RC0603-0_55-IPC_A|ModelType=PCBLIB|DatafileCount=1|ModelDatafileEntity0=FP-RC0603-0_55-IPC_A|ModelDatafileKind0=PCBLib|DatalinksLocked=T|DatabaseDatalinksLocked=T
|RECORD=46|OwnerIndex=627
|RECORD=48|OwnerIndex=627
|RECORD=17|IndexInSheet=32|OwnerPartId=-1|Style=4|ShowNetName=T|Location.X=534|Location.Y=155|Orientation=3|Color=128|FontID=1|Text=GND
|RECORD=17|IndexInSheet=33|OwnerPartId=-1|Style=4|ShowNetName=T|Location.X=444|Location.Y=155|Orientation=3|Color=128|FontID=1|Text=GND
|RECORD=17|IndexInSheet=34|OwnerPartId=-1|Style=4|ShowNetName=T|Location.X=614|Location.Y=155|Orientation=3|Color=128|FontID=1|Text=GND
|RECORD=17|IndexInSheet=35|OwnerPartId=-1|Style=4|ShowNetName=T|Location.X=364|Location.Y=155|Orientation=3|Color=128|FontID=1|Text=GND
|RECORD=17|IndexInSheet=36|OwnerPartId=-1|ShowNetName=T|Location.X=464|Location.Y=465|Orientation=1|Color=128|FontID=1|Text=+3.3V
|RECORD=17|IndexInSheet=37|OwnerPartId=-1|ShowNetName=T|Location.X=494|Location.Y=490|Orientation=1|Color=128|FontID=1|Text=+3.3V
|RECORD=4|IndexInSheet=38|OwnerPartId=-1|Location.X=764|Location.Y=555|Color=8388608|FontID=8|Text=LED DRIVER (0x6E)
|RECORD=17|IndexInSheet=39|OwnerPartId=-1|ShowNetName=T|Location.X=584|Location.Y=445|Orientation=2|Color=255|FontID=1|Text=SENS_I2C_SDA|IsCrossSheetConnector=T
|RECORD=17|IndexInSheet=40|OwnerPartId=-1|ShowNetName=T|Location.X=579|Location.Y=435|Orientation=2|Color=255|FontID=1|Text=SENS_I2C_SCL|IsCrossSheetConnector=T
|RECORD=1|LibReference=RES-2|ComponentDescription=Precision Thick Film Chip Resistor, 4.7 KOhm, +/- 1%, -55 to 155 degC, 0603 (1608 Metric), RoHS, Tape and Reel ERJ-3EKF4701V|PartCount=2|DisplayModeCount=1|IndexInSheet=41|OwnerPartId=-1|Location.X=564|Location.Y=185|Orientation=1|CurrentPartId=1|LibraryPath=*|SourceLibraryName=Altium Content Vault|TargetFileName=*|AreaColor=11599871|Color=128|PartIDLocked=T|DesignItemId=CMP-1012-00586-3|AllPinCount=2
|RECORD=2|OwnerIndex=639|OwnerPartId=1|FormalType=1|Electrical=4|PinConglomerate=33|PinLength=10|Location.X=564|Location.Y=205|Name=2|Designator=2|PinPropagationDelay=0.000000E+000
|RECORD=2|OwnerIndex=639|OwnerPartId=1|FormalType=1|Electrical=4|PinConglomerate=35|PinLength=10|Location.X=564|Location.Y=185|Name=1|Designator=1|PinPropagationDelay=0.000000E+000
|RECORD=6|OwnerIndex=639|IsNotAccesible=T|IndexInSheet=2|OwnerPartId=1|LineWidth=1|Color=16711680|LocationCount=10|X1=564|Y1=205|X2=564|Y2=201|X3=566|Y3=200|X4=562|Y4=198|X5=566|Y5=196|X6=562|Y6=194|X7=566|Y7=192|X8=562|Y8=190|X9=564|Y9=189|X10=564|Y10=185
|RECORD=41|OwnerIndex=639|IndexInSheet=3|OwnerPartId=-1|Location.X=561|Location.Y=217|Color=8388608|FontID=1|IsHidden=T|Text=220 Ohm|Name=Resistance
|RECORD=41|OwnerIndex=639|IndexInSheet=4|OwnerPartId=-1|Location.X=561|Location.Y=217|Color=8388608|FontID=1|IsHidden=T|Text=0603|Name=PackageReference
|RECORD=41|OwnerIndex=639|IndexInSheet=5|OwnerPartId=-1|Location.X=561|Location.Y=217|Color=8388608|FontID=1|IsHidden=T|Text=50 V|Name=Voltage Rating
|RECORD=41|OwnerIndex=639|IndexInSheet=6|OwnerPartId=-1|Location.X=561|Location.Y=217|Color=8388608|FontID=1|IsHidden=T|Text=125 degC|Name=Max Operating Temperature
|RECORD=41|OwnerIndex=639|IndexInSheet=7|OwnerPartId=-1|Location.X=561|Location.Y=217|Color=8388608|FontID=1|IsHidden=T|Text=4|Name=Elements
|RECORD=41|OwnerIndex=639|IndexInSheet=8|OwnerPartId=-1|Location.X=561|Location.Y=217|Color=8388608|FontID=1|IsHidden=T|Text=No SVHC|Name=REACH SVHC
|RECORD=41|OwnerIndex=639|IndexInSheet=9|OwnerPartId=-1|Location.X=561|Location.Y=217|Color=8388608|FontID=1|IsHidden=T|Text=0.063 inch|Name=Width
|RECORD=41|OwnerIndex=639|IndexInSheet=10|OwnerPartId=-1|Location.X=561|Location.Y=217|Color=8388608|FontID=1|IsHidden=T|Text=1205|Name=Case\Package
|RECORD=41|OwnerIndex=639|IndexInSheet=11|OwnerPartId=-1|Location.X=561|Location.Y=217|Color=8388608|FontID=1|IsHidden=T|Text=0.126 inch|Name=Length
|RECORD=41|OwnerIndex=639|IndexInSheet=12|OwnerPartId=-1|Location.X=561|Location.Y=217|Color=8388608|FontID=1|IsHidden=T|Text=0.024 inch|Name=Height
|RECORD=41|OwnerIndex=639|IndexInSheet=13|OwnerPartId=-1|Location.X=561|Location.Y=217|Color=8388608|FontID=1|IsHidden=T|Text=Surface Mount|Name=Mount
|RECORD=41|OwnerIndex=639|IndexInSheet=14|OwnerPartId=-1|Location.X=561|Location.Y=217|Color=8388608|FontID=1|IsHidden=T|Text=1|Name=Package Quantity
|RECORD=41|OwnerIndex=639|IndexInSheet=15|OwnerPartId=-1|Location.X=561|Location.Y=217|Color=8388608|FontID=1|IsHidden=T|Text=Apr-15|Name=DatasheetVersion
|RECORD=41|OwnerIndex=639|IndexInSheet=16|OwnerPartId=-1|Location.X=561|Location.Y=217|Color=8388608|FontID=1|IsHidden=T|Text=Manufacturer URL|Name=ComponentLink1Description
|RECORD=41|OwnerIndex=639|IndexInSheet=17|OwnerPartId=-1|Location.X=561|Location.Y=217|Color=8388608|FontID=1|IsHidden=T|Text=-55 degC|Name=Min Operating Temperature
|RECORD=41|OwnerIndex=639|IndexInSheet=18|OwnerPartId=-1|Location.X=561|Location.Y=217|Color=8388608|FontID=1|IsHidden=T|Text=Tape and Reel|Name=Packaging
|RECORD=41|OwnerIndex=639|IndexInSheet=19|OwnerPartId=-1|Location.X=561|Location.Y=217|Color=8388608|FontID=1|IsHidden=T|Text=No|Name=Radiation Hardening
|RECORD=41|OwnerIndex=639|IndexInSheet=20|OwnerPartId=-1|Location.X=561|Location.Y=217|Color=8388608|FontID=3|IsHidden=T|Text=http://industrial.panasonic.com/cdbs/www-data/pdf/RDA0000/AOA0000C86.pdf|Name=ComponentLink2URL
|RECORD=41|OwnerIndex=639|IndexInSheet=21|OwnerPartId=-1|Location.X=561|Location.Y=217|Color=8388608|FontID=1|IsHidden=T|Text=3216|Name=Case Code (Metric)
|RECORD=41|OwnerIndex=639|IndexInSheet=22|OwnerPartId=-1|Location.X=561|Location.Y=217|Color=8388608|FontID=1|IsHidden=T|Text=8|Name=Pins
|RECORD=41|OwnerIndex=639|IndexInSheet=23|OwnerPartId=-1|Location.X=561|Location.Y=217|Color=8388608|FontID=1|IsHidden=T|Text=1206|Name=Case Code (Imperial)
|RECORD=41|OwnerIndex=639|IndexInSheet=24|OwnerPartId=-1|Location.X=561|Location.Y=217|Color=8388608|FontID=1|IsHidden=T|Text=Thick Film|Name=Type (Resistor)
|RECORD=41|OwnerIndex=639|IndexInSheet=25|OwnerPartId=-1|Location.X=561|Location.Y=217|Color=8388608|FontID=1|IsHidden=T|Text=true|Name=RoHSCompliant
|RECORD=41|OwnerIndex=639|IndexInSheet=26|OwnerPartId=-1|Location.X=561|Location.Y=217|Color=8388608|FontID=1|IsHidden=T|Text=5%|Name=Tolerance
|RECORD=41|OwnerIndex=639|IndexInSheet=27|OwnerPartId=-1|Location.X=561|Location.Y=217|Color=8388608|FontID=1|IsHidden=T|Text=Datasheet|Name=ComponentLink2Description
|RECORD=41|OwnerIndex=639|IndexInSheet=28|OwnerPartId=-1|Location.X=561|Location.Y=217|Color=8388608|FontID=1|IsHidden=T|Text=2-Pin Surface Mount Device, Body 1.6 x 0.85 mm|Name=PackageDescription
|RECORD=41|OwnerIndex=639|IndexInSheet=29|OwnerPartId=-1|Location.X=561|Location.Y=217|Color=8388608|FontID=3|IsHidden=T|Text=http://www.panasonic.com/|Name=ComponentLink1URL
|RECORD=41|OwnerIndex=639|IndexInSheet=30|OwnerPartId=-1|Location.X=561|Location.Y=217|Color=8388608|FontID=1|IsHidden=T|Text=250 mW|Name=Power Rating
|RECORD=34|OwnerIndex=639|IndexInSheet=-1|OwnerPartId=-1|Location.X=567|Location.Y=196|Color=8388608|FontID=1|Text=R41|Name=Designator|ReadOnlyState=1
|RECORD=41|OwnerIndex=639|IndexInSheet=-1|OwnerPartId=-1|Location.X=567|Location.Y=186|Color=8388608|FontID=1|Text=4.7K|Name=Comment
|RECORD=44|OwnerIndex=639
|RECORD=45|OwnerIndex=675|IndexInSheet=-1|Description=Chip Resistor, 2-Leads, Body 1.75x0.95mm, IPC Medium Density|UseComponentLibrary=T|ModelName=RESC1608X55X30NL15T15|ModelType=PCBLIB|DatafileCount=1|ModelDatafileEntity0=RESC1608X55X30NL15T15|ModelDatafileKind0=PCBLib|IsCurrent=T|DatalinksLocked=T|DatabaseDatalinksLocked=T
|RECORD=46|OwnerIndex=676
|RECORD=48|OwnerIndex=676
|RECORD=41|OwnerIndex=678|IndexInSheet=-1|OwnerPartId=-1|Color=8388608|FontID=1|IsHidden=T|Text=2D|Name=Available Preview Images
|RECORD=45|OwnerIndex=675|IndexInSheet=-1|Description=Chip Resistor, 2-Leads, Body 1.75x0.95mm, IPC Low Density|UseComponentLibrary=T|ModelName=RESC1608X55X30ML15T15|ModelType=PCBLIB|DatafileCount=1|ModelDatafileEntity0=RESC1608X55X30ML15T15|ModelDatafileKind0=PCBLib|DatalinksLocked=T|DatabaseDatalinksLocked=T
|RECORD=46|OwnerIndex=680
|RECORD=48|OwnerIndex=680
|RECORD=41|OwnerIndex=682|IndexInSheet=-1|OwnerPartId=-1|Color=8388608|FontID=1|IsHidden=T|Text=2D|Name=Available Preview Images
|RECORD=45|OwnerIndex=675|IndexInSheet=-1|Description=Chip Resistor, 2-Leads, Body 1.75x0.95mm, IPC High Density|UseComponentLibrary=T|ModelName=RESC1608X55X30LL15T15|ModelType=PCBLIB|DatafileCount=1|ModelDatafileEntity0=RESC1608X55X30LL15T15|ModelDatafileKind0=PCBLib|DatalinksLocked=T|DatabaseDatalinksLocked=T
|RECORD=46|OwnerIndex=684
|RECORD=48|OwnerIndex=684
|RECORD=41|OwnerIndex=686|IndexInSheet=-1|OwnerPartId=-1|Color=8388608|FontID=1|IsHidden=T|Text=2D|Name=Available Preview Images
|RECORD=17|IndexInSheet=42|OwnerPartId=-1|Style=4|ShowNetName=T|Location.X=564|Location.Y=155|Orientation=3|Color=128|FontID=1|Text=GND
|RECORD=41|IndexInSheet=43|OwnerPartId=-1|Color=8388608|FontID=1|IsHidden=T|Name=ConfigurationParameters|ReadOnlyState=1
|RECORD=41|IndexInSheet=44|OwnerPartId=-1|Color=8388608|FontID=1|IsHidden=T|Name=ConfiguratorName|ReadOnlyState=1
|RECORD=41|IndexInSheet=45|OwnerPartId=-1|Color=8388608|FontID=1|IsHidden=T|Name=VersionControl_RevNumber|ReadOnlyState=1
|RECORD=41|IndexInSheet=46|OwnerPartId=-1|Color=8388608|FontID=1|IsHidden=T|Name=IsUserConfigurable|ReadOnlyState=1
|RECORD=41|IndexInSheet=47|OwnerPartId=-1|Color=8388608|FontID=1|IsHidden=T|Name=VersionControl_ProjFolderRevNumber|ReadOnlyState=1
|RECORD=41|IndexInSheet=48|OwnerPartId=-1|Color=8388608|FontID=1|IsHidden=T|Name=SPICEModelCache|ReadOnlyState=1
|RECORD=1|LibReference=RES-2|ComponentDescription=Chip Resistor, 4.7 KOhm, +/- 1%, 0.1 W, -55 to 155 degC, 0402 (1005 Metric), RoHS, Tape and Reel|PartCount=2|DisplayModeCount=1|IndexInSheet=49|OwnerPartId=-1|Location.X=364|Location.Y=425|Orientation=3|CurrentPartId=1|LibraryPath=*|SourceLibraryName=Altium Content Vault|TargetFileName=*|AreaColor=11599871|Color=128|PartIDLocked=T|DesignItemId=CMP-2002-01154-4|AllPinCount=2
|RECORD=2|OwnerIndex=695|OwnerPartId=1|FormalType=1|Electrical=4|PinConglomerate=35|PinLength=10|Location.X=364|Location.Y=405|Name=2|Designator=2|PinPropagationDelay=0.000000E+000
|RECORD=2|OwnerIndex=695|OwnerPartId=1|FormalType=1|Electrical=4|PinConglomerate=33|PinLength=10|Location.X=364|Location.Y=425|Name=1|Designator=1|PinPropagationDelay=0.000000E+000
|RECORD=6|OwnerIndex=695|IsNotAccesible=T|IndexInSheet=2|OwnerPartId=1|LineWidth=1|Color=16711680|LocationCount=10|X1=364|Y1=405|X2=364|Y2=409|X3=362|Y3=410|X4=366|Y4=412|X5=362|Y5=414|X6=366|Y6=416|X7=362|Y7=418|X8=366|Y8=420|X9=364|Y9=421|X10=364|Y10=425
|RECORD=41|OwnerIndex=695|IndexInSheet=3|OwnerPartId=-1|Location.X=361|Location.Y=437|Color=8388608|FontID=1|IsHidden=T|Text=0.35 mm|Name=Height
|RECORD=41|OwnerIndex=695|IndexInSheet=4|OwnerPartId=-1|Location.X=361|Location.Y=437|Color=8388608|FontID=1|IsHidden=T|Text=Surface Mount|Name=Mounting Technology
|RECORD=41|OwnerIndex=695|IndexInSheet=5|OwnerPartId=-1|Location.X=361|Location.Y=437|Color=8388608|FontID=1|IsHidden=T|Text=Yes|Name=REACH SVHC
|RECORD=41|OwnerIndex=695|IndexInSheet=6|OwnerPartId=-1|Location.X=361|Location.Y=437|Color=8388608|FontID=1|IsHidden=T|Text=4.7 KOhm|Name=Resistance
|RECORD=41|OwnerIndex=695|IndexInSheet=7|OwnerPartId=-1|Location.X=361|Location.Y=437|Color=8388608|FontID=1|IsHidden=T|Text=155 degC|Name=Max Operating Temperature
|RECORD=41|OwnerIndex=695|IndexInSheet=8|OwnerPartId=-1|Location.X=361|Location.Y=437|Color=8388608|FontID=1|IsHidden=T|Text=Manufacturer URL|Name=ComponentLink1Description
|RECORD=41|OwnerIndex=695|IndexInSheet=9|OwnerPartId=-1|Location.X=361|Location.Y=437|Color=8388608|FontID=1|IsHidden=T|Text=Datasheet|Name=ComponentLink2Description
|RECORD=41|OwnerIndex=695|IndexInSheet=10|OwnerPartId=-1|Location.X=361|Location.Y=437|Color=8388608|FontID=1|IsHidden=T|Text=2|Name=Pins
|RECORD=41|OwnerIndex=695|IndexInSheet=11|OwnerPartId=-1|Location.X=361|Location.Y=437|Color=8388608|FontID=1|IsHidden=T|Text=0402|Name=PackageReference
|RECORD=41|OwnerIndex=695|IndexInSheet=12|OwnerPartId=-1|Location.X=361|Location.Y=437|Color=8388608|FontID=1|IsHidden=T|Text=1%|Name=Tolerance
|RECORD=41|OwnerIndex=695|IndexInSheet=13|OwnerPartId=-1|Location.X=361|Location.Y=437|Color=8388608|FontID=1|IsHidden=T|Text=0402|Name=Case Code (Imperial)
|RECORD=41|OwnerIndex=695|IndexInSheet=14|OwnerPartId=-1|Location.X=361|Location.Y=437|Color=8388608|FontID=1|IsHidden=T|Text=1 mm|Name=Length
|RECORD=41|OwnerIndex=695|IndexInSheet=15|OwnerPartId=-1|Location.X=361|Location.Y=437|Color=8388608|FontID=1|IsHidden=T|Text=2-Pin Surface Mount Device, Body 1 x 0.5 mm|Name=PackageDescription
|RECORD=41|OwnerIndex=695|IndexInSheet=16|OwnerPartId=-1|Location.X=361|Location.Y=437|Color=8388608|FontID=1|IsHidden=T|Text=ERJ-2RKF4701X|Name=PartNumber
|RECORD=41|OwnerIndex=695|IndexInSheet=17|OwnerPartId=-1|Location.X=361|Location.Y=437|Color=8388608|FontID=1|IsHidden=T|Text=true|Name=RoHSCompliant
|RECORD=41|OwnerIndex=695|IndexInSheet=18|OwnerPartId=-1|Location.X=361|Location.Y=437|Color=8388608|FontID=1|IsHidden=T|Text=1|Name=Package Quantity
|RECORD=41|OwnerIndex=695|IndexInSheet=19|OwnerPartId=-1|Location.X=361|Location.Y=437|Color=8388608|FontID=1|IsHidden=T|Text=No|Name=Radiation Hardening
|RECORD=41|OwnerIndex=695|IndexInSheet=20|OwnerPartId=-1|Location.X=361|Location.Y=437|Color=8388608|FontID=1|IsHidden=T|Text=04/2015|Name=DatasheetVersion
|RECORD=41|OwnerIndex=695|IndexInSheet=21|OwnerPartId=-1|Location.X=361|Location.Y=437|Color=8388608|FontID=1|IsHidden=T|Text=0.5 mm|Name=Width
|RECORD=41|OwnerIndex=695|IndexInSheet=22|OwnerPartId=-1|Location.X=361|Location.Y=437|Color=8388608|FontID=1|IsHidden=T|Text=1005|Name=Case Code (Metric)
|RECORD=41|OwnerIndex=695|IndexInSheet=23|OwnerPartId=-1|Location.X=361|Location.Y=437|Color=8388608|FontID=1|IsHidden=T|Text=50 V|Name=Voltage Rating
|RECORD=41|OwnerIndex=695|IndexInSheet=24|OwnerPartId=-1|Location.X=361|Location.Y=437|Color=8388608|FontID=1|IsHidden=T|Text=0402|Name=Case\/Package
|RECORD=41|OwnerIndex=695|IndexInSheet=25|OwnerPartId=-1|Location.X=361|Location.Y=437|Color=8388608|FontID=1|IsHidden=T|Text=Surface Mount|Name=Mount
|RECORD=41|OwnerIndex=695|IndexInSheet=26|OwnerPartId=-1|Location.X=361|Location.Y=437|Color=8388608|FontID=3|IsHidden=T|Text=http://www.panasonic.com/|Name=ComponentLink1URL
|RECORD=41|OwnerIndex=695|IndexInSheet=27|OwnerPartId=-1|Location.X=361|Location.Y=437|Color=8388608|FontID=1|IsHidden=T|Text=-55 degC|Name=Min Operating Temperature
|RECORD=41|OwnerIndex=695|IndexInSheet=28|OwnerPartId=-1|Location.X=361|Location.Y=437|Color=8388608|FontID=1|IsHidden=T|Text=100 mW|Name=Power Rating
|RECORD=41|OwnerIndex=695|IndexInSheet=29|OwnerPartId=-1|Location.X=361|Location.Y=437|Color=8388608|FontID=1|IsHidden=T|Text=Cut Tape|Name=Packaging
|RECORD=41|OwnerIndex=695|IndexInSheet=30|OwnerPartId=-1|Location.X=361|Location.Y=437|Color=8388608|FontID=3|IsHidden=T|Text=http://industrial.panasonic.com/cdbs/www-data/pdf/RDA0000/AOA0000C86.pdf|Name=ComponentLink2URL
|RECORD=34|OwnerIndex=695|IndexInSheet=-1|OwnerPartId=-1|Location.X=367|Location.Y=416|Color=8388608|FontID=1|Text=R109|Name=Designator|ReadOnlyState=1
|RECORD=41|OwnerIndex=695|IndexInSheet=-1|OwnerPartId=-1|Location.X=367|Location.Y=406|Color=8388608|FontID=1|Text=4.7K_0402|Name=Comment
|RECORD=44|OwnerIndex=695
|RECORD=45|OwnerIndex=731|IndexInSheet=-1|Description=Chip Resistor, 2-Leads, Body 1.05x0.55mm, IPC High Density|UseComponentLibrary=T|ModelName=RESC1005X40X25LL05T05|ModelType=PCBLIB|DatafileCount=1|ModelDatafileEntity0=RESC1005X40X25LL05T05|ModelDatafileKind0=PCBLib|IsCurrent=T|DatalinksLocked=T|DatabaseDatalinksLocked=T
|RECORD=46|OwnerIndex=732
|RECORD=48|OwnerIndex=732
|RECORD=41|OwnerIndex=734|IndexInSheet=-1|OwnerPartId=-1|Color=8388608|FontID=1|IsHidden=T|Text=2D|Name=Available Preview Images
|RECORD=45|OwnerIndex=731|IndexInSheet=-1|Description=Chip Resistor, 2-Leads, Body 1.05x0.55mm, IPC Low Density|UseComponentLibrary=T|ModelName=RESC1005X40X25ML05T05|ModelType=PCBLIB|DatafileCount=1|ModelDatafileEntity0=RESC1005X40X25ML05T05|ModelDatafileKind0=PCBLib|DatalinksLocked=T|DatabaseDatalinksLocked=T
|RECORD=46|OwnerIndex=736
|RECORD=48|OwnerIndex=736
|RECORD=41|OwnerIndex=738|IndexInSheet=-1|OwnerPartId=-1|Color=8388608|FontID=1|IsHidden=T|Text=2D|Name=Available Preview Images
|RECORD=45|OwnerIndex=731|IndexInSheet=-1|Description=Chip Resistor, 2-Leads, Body 1.05x0.55mm, IPC Medium Density|UseComponentLibrary=T|ModelName=RESC1005X40X25NL05T05|ModelType=PCBLIB|DatafileCount=1|ModelDatafileEntity0=RESC1005X40X25NL05T05|ModelDatafileKind0=PCBLib|DatalinksLocked=T|DatabaseDatalinksLocked=T
|RECORD=46|OwnerIndex=740
|RECORD=48|OwnerIndex=740
|RECORD=41|OwnerIndex=742|IndexInSheet=-1|OwnerPartId=-1|Color=8388608|FontID=1|IsHidden=T|Text=2D|Name=Available Preview Images
|RECORD=17|IndexInSheet=50|OwnerPartId=-1|ShowNetName=T|Location.X=364|Location.Y=455|Orientation=1|Color=128|FontID=1|Text=+3.3V
|RECORD=1|LibReference=RES-2|ComponentDescription=Chip Resistor, 4.7 KOhm, +/- 1%, 0.1 W, -55 to 155 degC, 0402 (1005 Metric), RoHS, Tape and Reel|PartCount=2|DisplayModeCount=1|IndexInSheet=51|OwnerPartId=-1|Location.X=494|Location.Y=240|Orientation=3|CurrentPartId=1|LibraryPath=*|SourceLibraryName=Altium Content Vault|TargetFileName=*|AreaColor=11599871|Color=128|PartIDLocked=T|DesignItemId=CMP-2002-01154-4|AllPinCount=2|ComponentKindVersion2=5
|RECORD=2|OwnerIndex=745|OwnerPartId=1|FormalType=1|Electrical=4|PinConglomerate=35|PinLength=10|Location.X=494|Location.Y=220|Name=2|Designator=2|PinPropagationDelay=0.000000E+000
|RECORD=2|OwnerIndex=745|OwnerPartId=1|FormalType=1|Electrical=4|PinConglomerate=33|PinLength=10|Location.X=494|Location.Y=240|Name=1|Designator=1|PinPropagationDelay=0.000000E+000
|RECORD=6|OwnerIndex=745|IsNotAccesible=T|IndexInSheet=2|OwnerPartId=1|LineWidth=1|Color=16711680|LocationCount=10|X1=494|Y1=220|X2=494|Y2=224|X3=492|Y3=225|X4=496|Y4=227|X5=492|Y5=229|X6=496|Y6=231|X7=492|Y7=233|X8=496|Y8=235|X9=494|Y9=236|X10=494|Y10=240
|RECORD=41|OwnerIndex=745|IndexInSheet=3|OwnerPartId=-1|Location.X=491|Location.Y=252|Color=8388608|FontID=1|IsHidden=T|Text=0.35 mm|Name=Height
|RECORD=41|OwnerIndex=745|IndexInSheet=4|OwnerPartId=-1|Location.X=491|Location.Y=252|Color=8388608|FontID=1|IsHidden=T|Text=Surface Mount|Name=Mounting Technology
|RECORD=41|OwnerIndex=745|IndexInSheet=5|OwnerPartId=-1|Location.X=491|Location.Y=252|Color=8388608|FontID=1|IsHidden=T|Text=Yes|Name=REACH SVHC
|RECORD=41|OwnerIndex=745|IndexInSheet=6|OwnerPartId=-1|Location.X=491|Location.Y=252|Color=8388608|FontID=1|IsHidden=T|Text=4.7 KOhm|Name=Resistance
|RECORD=41|OwnerIndex=745|IndexInSheet=7|OwnerPartId=-1|Location.X=491|Location.Y=252|Color=8388608|FontID=1|IsHidden=T|Text=155 degC|Name=Max Operating Temperature
|RECORD=41|OwnerIndex=745|IndexInSheet=8|OwnerPartId=-1|Location.X=491|Location.Y=252|Color=8388608|FontID=1|IsHidden=T|Text=Manufacturer URL|Name=ComponentLink1Description
|RECORD=41|OwnerIndex=745|IndexInSheet=9|OwnerPartId=-1|Location.X=491|Location.Y=252|Color=8388608|FontID=1|IsHidden=T|Text=Datasheet|Name=ComponentLink2Description
|RECORD=41|OwnerIndex=745|IndexInSheet=10|OwnerPartId=-1|Location.X=491|Location.Y=252|Color=8388608|FontID=1|IsHidden=T|Text=2|Name=Pins
|RECORD=41|OwnerIndex=745|IndexInSheet=11|OwnerPartId=-1|Location.X=491|Location.Y=252|Color=8388608|FontID=1|IsHidden=T|Text=0402|Name=PackageReference
|RECORD=41|OwnerIndex=745|IndexInSheet=12|OwnerPartId=-1|Location.X=491|Location.Y=252|Color=8388608|FontID=1|IsHidden=T|Text=1%|Name=Tolerance
|RECORD=41|OwnerIndex=745|IndexInSheet=13|OwnerPartId=-1|Location.X=491|Location.Y=252|Color=8388608|FontID=1|IsHidden=T|Text=0402|Name=Case Code (Imperial)
|RECORD=41|OwnerIndex=745|IndexInSheet=14|OwnerPartId=-1|Location.X=491|Location.Y=252|Color=8388608|FontID=1|IsHidden=T|Text=1 mm|Name=Length
|RECORD=41|OwnerIndex=745|IndexInSheet=15|OwnerPartId=-1|Location.X=491|Location.Y=252|Color=8388608|FontID=1|IsHidden=T|Text=2-Pin Surface Mount Device, Body 1 x 0.5 mm|Name=PackageDescription
|RECORD=41|OwnerIndex=745|IndexInSheet=16|OwnerPartId=-1|Location.X=491|Location.Y=252|Color=8388608|FontID=1|IsHidden=T|Text=ERJ-2RKF4701X|Name=PartNumber
|RECORD=41|OwnerIndex=745|IndexInSheet=17|OwnerPartId=-1|Location.X=491|Location.Y=252|Color=8388608|FontID=1|IsHidden=T|Text=true|Name=RoHSCompliant
|RECORD=41|OwnerIndex=745|IndexInSheet=18|OwnerPartId=-1|Location.X=491|Location.Y=252|Color=8388608|FontID=1|IsHidden=T|Text=1|Name=Package Quantity
|RECORD=41|OwnerIndex=745|IndexInSheet=19|OwnerPartId=-1|Location.X=491|Location.Y=252|Color=8388608|FontID=1|IsHidden=T|Text=No|Name=Radiation Hardening
|RECORD=41|OwnerIndex=745|IndexInSheet=20|OwnerPartId=-1|Location.X=491|Location.Y=252|Color=8388608|FontID=1|IsHidden=T|Text=04/2015|Name=DatasheetVersion
|RECORD=41|OwnerIndex=745|IndexInSheet=21|OwnerPartId=-1|Location.X=491|Location.Y=252|Color=8388608|FontID=1|IsHidden=T|Text=0.5 mm|Name=Width
|RECORD=41|OwnerIndex=745|IndexInSheet=22|OwnerPartId=-1|Location.X=491|Location.Y=252|Color=8388608|FontID=1|IsHidden=T|Text=1005|Name=Case Code (Metric)
|RECORD=41|OwnerIndex=745|IndexInSheet=23|OwnerPartId=-1|Location.X=491|Location.Y=252|Color=8388608|FontID=1|IsHidden=T|Text=50 V|Name=Voltage Rating
|RECORD=41|OwnerIndex=745|IndexInSheet=24|OwnerPartId=-1|Location.X=491|Location.Y=252|Color=8388608|FontID=1|IsHidden=T|Text=0402|Name=Case\/Package
|RECORD=41|OwnerIndex=745|IndexInSheet=25|OwnerPartId=-1|Location.X=491|Location.Y=252|Color=8388608|FontID=1|IsHidden=T|Text=Surface Mount|Name=Mount
|RECORD=41|OwnerIndex=745|IndexInSheet=26|OwnerPartId=-1|Location.X=491|Location.Y=252|Color=8388608|FontID=3|IsHidden=T|Text=http://www.panasonic.com/|Name=ComponentLink1URL
|RECORD=41|OwnerIndex=745|IndexInSheet=27|OwnerPartId=-1|Location.X=491|Location.Y=252|Color=8388608|FontID=1|IsHidden=T|Text=-55 degC|Name=Min Operating Temperature
|RECORD=41|OwnerIndex=745|IndexInSheet=28|OwnerPartId=-1|Location.X=491|Location.Y=252|Color=8388608|FontID=1|IsHidden=T|Text=100 mW|Name=Power Rating
|RECORD=41|OwnerIndex=745|IndexInSheet=29|OwnerPartId=-1|Location.X=491|Location.Y=252|Color=8388608|FontID=1|IsHidden=T|Text=Cut Tape|Name=Packaging
|RECORD=41|OwnerIndex=745|IndexInSheet=30|OwnerPartId=-1|Location.X=491|Location.Y=252|Color=8388608|FontID=3|IsHidden=T|Text=http://industrial.panasonic.com/cdbs/www-data/pdf/RDA0000/AOA0000C86.pdf|Name=ComponentLink2URL
|RECORD=34|OwnerIndex=745|IndexInSheet=-1|OwnerPartId=-1|Location.X=489|Location.Y=215|Orientation=1|Color=8388608|FontID=2|Text=R110|Name=Designator|ReadOnlyState=1
|RECORD=41|OwnerIndex=745|IndexInSheet=-1|OwnerPartId=-1|Location.X=509|Location.Y=190|Orientation=1|Color=8388608|FontID=2|Text=DNI_4.7K_0402|Name=Comment
|RECORD=44|OwnerIndex=745
|RECORD=45|OwnerIndex=781|IndexInSheet=-1|Description=Chip Resistor, 2-Leads, Body 1.05x0.55mm, IPC High Density|UseComponentLibrary=T|ModelName=RESC1005X40X25LL05T05|ModelType=PCBLIB|DatafileCount=1|ModelDatafileEntity0=RESC1005X40X25LL05T05|ModelDatafileKind0=PCBLib|IsCurrent=T|DatalinksLocked=T|DatabaseDatalinksLocked=T
|RECORD=46|OwnerIndex=782
|RECORD=48|OwnerIndex=782
|RECORD=41|OwnerIndex=784|IndexInSheet=-1|OwnerPartId=-1|Color=8388608|FontID=1|IsHidden=T|Text=2D|Name=Available Preview Images
|RECORD=45|OwnerIndex=781|IndexInSheet=-1|Description=Chip Resistor, 2-Leads, Body 1.05x0.55mm, IPC Low Density|UseComponentLibrary=T|ModelName=RESC1005X40X25ML05T05|ModelType=PCBLIB|DatafileCount=1|ModelDatafileEntity0=RESC1005X40X25ML05T05|ModelDatafileKind0=PCBLib|DatalinksLocked=T|DatabaseDatalinksLocked=T
|RECORD=46|OwnerIndex=786
|RECORD=48|OwnerIndex=786
|RECORD=41|OwnerIndex=788|IndexInSheet=-1|OwnerPartId=-1|Color=8388608|FontID=1|IsHidden=T|Text=2D|Name=Available Preview Images
|RECORD=45|OwnerIndex=781|IndexInSheet=-1|Description=Chip Resistor, 2-Leads, Body 1.05x0.55mm, IPC Medium Density|UseComponentLibrary=T|ModelName=RESC1005X40X25NL05T05|ModelType=PCBLIB|DatafileCount=1|ModelDatafileEntity0=RESC1005X40X25NL05T05|ModelDatafileKind0=PCBLib|DatalinksLocked=T|DatabaseDatalinksLocked=T
|RECORD=46|OwnerIndex=790
|RECORD=48|OwnerIndex=790
|RECORD=41|OwnerIndex=792|IndexInSheet=-1|OwnerPartId=-1|Color=8388608|FontID=1|IsHidden=T|Text=2D|Name=Available Preview Images
|RECORD=17|IndexInSheet=52|OwnerPartId=-1|Style=4|ShowNetName=T|Location.X=494|Location.Y=150|Orientation=3|Color=128|FontID=1|Text=GND
|RECORD=1|LibReference=RES-2|ComponentDescription=Chip Resistor, 4.7 KOhm, +/- 1%, 0.1 W, -55 to 155 degC, 0402 (1005 Metric), RoHS, Tape and Reel|PartCount=2|DisplayModeCount=1|IndexInSheet=53|OwnerPartId=-1|Location.X=494|Location.Y=470|Orientation=3|CurrentPartId=1|LibraryPath=*|SourceLibraryName=Altium Content Vault|TargetFileName=*|AreaColor=11599871|Color=128|PartIDLocked=T|DesignItemId=CMP-2002-01154-4|AllPinCount=2
|RECORD=2|OwnerIndex=795|OwnerPartId=1|FormalType=1|Electrical=4|PinConglomerate=35|PinLength=10|Location.X=494|Location.Y=450|Name=2|Designator=2|PinPropagationDelay=0.000000E+000
|RECORD=2|OwnerIndex=795|OwnerPartId=1|FormalType=1|Electrical=4|PinConglomerate=33|PinLength=10|Location.X=494|Location.Y=470|Name=1|Designator=1|PinPropagationDelay=0.000000E+000
|RECORD=6|OwnerIndex=795|IsNotAccesible=T|IndexInSheet=2|OwnerPartId=1|LineWidth=1|Color=16711680|LocationCount=10|X1=494|Y1=450|X2=494|Y2=454|X3=492|Y3=455|X4=496|Y4=457|X5=492|Y5=459|X6=496|Y6=461|X7=492|Y7=463|X8=496|Y8=465|X9=494|Y9=466|X10=494|Y10=470
|RECORD=41|OwnerIndex=795|IndexInSheet=3|OwnerPartId=-1|Location.X=491|Location.Y=482|Color=8388608|FontID=1|IsHidden=T|Text=0.35 mm|Name=Height
|RECORD=41|OwnerIndex=795|IndexInSheet=4|OwnerPartId=-1|Location.X=491|Location.Y=482|Color=8388608|FontID=1|IsHidden=T|Text=Surface Mount|Name=Mounting Technology
|RECORD=41|OwnerIndex=795|IndexInSheet=5|OwnerPartId=-1|Location.X=491|Location.Y=482|Color=8388608|FontID=1|IsHidden=T|Text=Yes|Name=REACH SVHC
|RECORD=41|OwnerIndex=795|IndexInSheet=6|OwnerPartId=-1|Location.X=491|Location.Y=482|Color=8388608|FontID=1|IsHidden=T|Text=4.7 KOhm|Name=Resistance
|RECORD=41|OwnerIndex=795|IndexInSheet=7|OwnerPartId=-1|Location.X=491|Location.Y=482|Color=8388608|FontID=1|IsHidden=T|Text=155 degC|Name=Max Operating Temperature
|RECORD=41|OwnerIndex=795|IndexInSheet=8|OwnerPartId=-1|Location.X=491|Location.Y=482|Color=8388608|FontID=1|IsHidden=T|Text=Manufacturer URL|Name=ComponentLink1Description
|RECORD=41|OwnerIndex=795|IndexInSheet=9|OwnerPartId=-1|Location.X=491|Location.Y=482|Color=8388608|FontID=1|IsHidden=T|Text=Datasheet|Name=ComponentLink2Description
|RECORD=41|OwnerIndex=795|IndexInSheet=10|OwnerPartId=-1|Location.X=491|Location.Y=482|Color=8388608|FontID=1|IsHidden=T|Text=2|Name=Pins
|RECORD=41|OwnerIndex=795|IndexInSheet=11|OwnerPartId=-1|Location.X=491|Location.Y=482|Color=8388608|FontID=1|IsHidden=T|Text=0402|Name=PackageReference
|RECORD=41|OwnerIndex=795|IndexInSheet=12|OwnerPartId=-1|Location.X=491|Location.Y=482|Color=8388608|FontID=1|IsHidden=T|Text=1%|Name=Tolerance
|RECORD=41|OwnerIndex=795|IndexInSheet=13|OwnerPartId=-1|Location.X=491|Location.Y=482|Color=8388608|FontID=1|IsHidden=T|Text=0402|Name=Case Code (Imperial)
|RECORD=41|OwnerIndex=795|IndexInSheet=14|OwnerPartId=-1|Location.X=491|Location.Y=482|Color=8388608|FontID=1|IsHidden=T|Text=1 mm|Name=Length
|RECORD=41|OwnerIndex=795|IndexInSheet=15|OwnerPartId=-1|Location.X=491|Location.Y=482|Color=8388608|FontID=1|IsHidden=T|Text=2-Pin Surface Mount Device, Body 1 x 0.5 mm|Name=PackageDescription
|RECORD=41|OwnerIndex=795|IndexInSheet=16|OwnerPartId=-1|Location.X=491|Location.Y=482|Color=8388608|FontID=1|IsHidden=T|Text=ERJ-2RKF4701X|Name=PartNumber
|RECORD=41|OwnerIndex=795|IndexInSheet=17|OwnerPartId=-1|Location.X=491|Location.Y=482|Color=8388608|FontID=1|IsHidden=T|Text=true|Name=RoHSCompliant
|RECORD=41|OwnerIndex=795|IndexInSheet=18|OwnerPartId=-1|Location.X=491|Location.Y=482|Color=8388608|FontID=1|IsHidden=T|Text=1|Name=Package Quantity
|RECORD=41|OwnerIndex=795|IndexInSheet=19|OwnerPartId=-1|Location.X=491|Location.Y=482|Color=8388608|FontID=1|IsHidden=T|Text=No|Name=Radiation Hardening
|RECORD=41|OwnerIndex=795|IndexInSheet=20|OwnerPartId=-1|Location.X=491|Location.Y=482|Color=8388608|FontID=1|IsHidden=T|Text=04/2015|Name=DatasheetVersion
|RECORD=41|OwnerIndex=795|IndexInSheet=21|OwnerPartId=-1|Location.X=491|Location.Y=482|Color=8388608|FontID=1|IsHidden=T|Text=0.5 mm|Name=Width
|RECORD=41|OwnerIndex=795|IndexInSheet=22|OwnerPartId=-1|Location.X=491|Location.Y=482|Color=8388608|FontID=1|IsHidden=T|Text=1005|Name=Case Code (Metric)
|RECORD=41|OwnerIndex=795|IndexInSheet=23|OwnerPartId=-1|Location.X=491|Location.Y=482|Color=8388608|FontID=1|IsHidden=T|Text=50 V|Name=Voltage Rating
|RECORD=41|OwnerIndex=795|IndexInSheet=24|OwnerPartId=-1|Location.X=491|Location.Y=482|Color=8388608|FontID=1|IsHidden=T|Text=0402|Name=Case\/Package
|RECORD=41|OwnerIndex=795|IndexInSheet=25|OwnerPartId=-1|Location.X=491|Location.Y=482|Color=8388608|FontID=1|IsHidden=T|Text=Surface Mount|Name=Mount
|RECORD=41|OwnerIndex=795|IndexInSheet=26|OwnerPartId=-1|Location.X=491|Location.Y=482|Color=8388608|FontID=3|IsHidden=T|Text=http://www.panasonic.com/|Name=ComponentLink1URL
|RECORD=41|OwnerIndex=795|IndexInSheet=27|OwnerPartId=-1|Location.X=491|Location.Y=482|Color=8388608|FontID=1|IsHidden=T|Text=-55 degC|Name=Min Operating Temperature
|RECORD=41|OwnerIndex=795|IndexInSheet=28|OwnerPartId=-1|Location.X=491|Location.Y=482|Color=8388608|FontID=1|IsHidden=T|Text=100 mW|Name=Power Rating
|RECORD=41|OwnerIndex=795|IndexInSheet=29|OwnerPartId=-1|Location.X=491|Location.Y=482|Color=8388608|FontID=1|IsHidden=T|Text=Cut Tape|Name=Packaging
|RECORD=41|OwnerIndex=795|IndexInSheet=30|OwnerPartId=-1|Location.X=491|Location.Y=482|Color=8388608|FontID=3|IsHidden=T|Text=http://industrial.panasonic.com/cdbs/www-data/pdf/RDA0000/AOA0000C86.pdf|Name=ComponentLink2URL
|RECORD=34|OwnerIndex=795|IndexInSheet=-1|OwnerPartId=-1|Location.X=497|Location.Y=461|Color=8388608|FontID=1|Text=R108|Name=Designator|ReadOnlyState=1
|RECORD=41|OwnerIndex=795|IndexInSheet=-1|OwnerPartId=-1|Location.X=497|Location.Y=451|Color=8388608|FontID=1|Text=4.7K_0402|Name=Comment
|RECORD=44|OwnerIndex=795
|RECORD=45|OwnerIndex=831|IndexInSheet=-1|Description=Chip Resistor, 2-Leads, Body 1.05x0.55mm, IPC High Density|UseComponentLibrary=T|ModelName=RESC1005X40X25LL05T05|ModelType=PCBLIB|DatafileCount=1|ModelDatafileEntity0=RESC1005X40X25LL05T05|ModelDatafileKind0=PCBLib|IsCurrent=T|DatalinksLocked=T|DatabaseDatalinksLocked=T
|RECORD=46|OwnerIndex=832
|RECORD=48|OwnerIndex=832
|RECORD=41|OwnerIndex=834|IndexInSheet=-1|OwnerPartId=-1|Color=8388608|FontID=1|IsHidden=T|Text=2D|Name=Available Preview Images
|RECORD=45|OwnerIndex=831|IndexInSheet=-1|Description=Chip Resistor, 2-Leads, Body 1.05x0.55mm, IPC Low Density|UseComponentLibrary=T|ModelName=RESC1005X40X25ML05T05|ModelType=PCBLIB|DatafileCount=1|ModelDatafileEntity0=RESC1005X40X25ML05T05|ModelDatafileKind0=PCBLib|DatalinksLocked=T|DatabaseDatalinksLocked=T
|RECORD=46|OwnerIndex=836
|RECORD=48|OwnerIndex=836
|RECORD=41|OwnerIndex=838|IndexInSheet=-1|OwnerPartId=-1|Color=8388608|FontID=1|IsHidden=T|Text=2D|Name=Available Preview Images
|RECORD=45|OwnerIndex=831|IndexInSheet=-1|Description=Chip Resistor, 2-Leads, Body 1.05x0.55mm, IPC Medium Density|UseComponentLibrary=T|ModelName=RESC1005X40X25NL05T05|ModelType=PCBLIB|DatafileCount=1|ModelDatafileEntity0=RESC1005X40X25NL05T05|ModelDatafileKind0=PCBLib|DatalinksLocked=T|DatabaseDatalinksLocked=T
|RECORD=46|OwnerIndex=840
|RECORD=48|OwnerIndex=840
|RECORD=41|OwnerIndex=842|IndexInSheet=-1|OwnerPartId=-1|Color=8388608|FontID=1|IsHidden=T|Text=2D|Name=Available Preview Images
|RECORD=41|IndexInSheet=54|OwnerPartId=-1|Color=8388608|FontID=1|IsHidden=T|Text=*|Name=CurrentTime|ReadOnlyState=1
|RECORD=41|IndexInSheet=55|OwnerPartId=-1|Color=8388608|FontID=1|IsHidden=T|Text=*|Name=CurrentDate|ReadOnlyState=1
|RECORD=41|IndexInSheet=56|OwnerPartId=-1|Color=8388608|FontID=1|IsHidden=T|Text=*|Name=Time|ReadOnlyState=1
|RECORD=41|IndexInSheet=57|OwnerPartId=-1|Color=8388608|FontID=1|IsHidden=T|Text=*|Name=Date|ReadOnlyState=1
|RECORD=41|IndexInSheet=58|OwnerPartId=-1|Color=8388608|FontID=1|IsHidden=T|Text=*|Name=DocumentFullPathAndName|ReadOnlyState=1
|RECORD=41|IndexInSheet=59|OwnerPartId=-1|Color=8388608|FontID=1|IsHidden=T|Text=*|Name=DocumentName|ReadOnlyState=1
|RECORD=41|IndexInSheet=60|OwnerPartId=-1|Color=8388608|FontID=1|IsHidden=T|Text=*|Name=ModifiedDate|ReadOnlyState=1
|RECORD=41|IndexInSheet=61|OwnerPartId=-1|Color=8388608|FontID=1|IsHidden=T|Text=*|Name=ApprovedBy|ReadOnlyState=1
|RECORD=41|IndexInSheet=62|OwnerPartId=-1|Color=8388608|FontID=1|IsHidden=T|Text=*|Name=CheckedBy|ReadOnlyState=1
|RECORD=41|IndexInSheet=63|OwnerPartId=-1|Color=8388608|FontID=1|IsHidden=T|Text=*|Name=Author|ReadOnlyState=1
|RECORD=41|IndexInSheet=64|OwnerPartId=-1|Color=8388608|FontID=1|IsHidden=T|Text=*|Name=CompanyName|ReadOnlyState=1
|RECORD=41|IndexInSheet=65|OwnerPartId=-1|Color=8388608|FontID=1|IsHidden=T|Text=*|Name=DrawnBy|ReadOnlyState=1
|RECORD=41|IndexInSheet=66|OwnerPartId=-1|Color=8388608|FontID=1|IsHidden=T|Text=*|Name=Engineer|ReadOnlyState=1
|RECORD=41|IndexInSheet=67|OwnerPartId=-1|Color=8388608|FontID=1|IsHidden=T|Text=*|Name=Organization|ReadOnlyState=1
|RECORD=41|IndexInSheet=68|OwnerPartId=-1|Color=8388608|FontID=1|IsHidden=T|Text=*|Name=Address1|ReadOnlyState=1
|RECORD=41|IndexInSheet=69|OwnerPartId=-1|Color=8388608|FontID=1|IsHidden=T|Text=*|Name=Address2|ReadOnlyState=1
|RECORD=41|IndexInSheet=70|OwnerPartId=-1|Color=8388608|FontID=1|IsHidden=T|Text=*|Name=Address3|ReadOnlyState=1
|RECORD=41|IndexInSheet=71|OwnerPartId=-1|Color=8388608|FontID=1|IsHidden=T|Text=*|Name=Address4|ReadOnlyState=1
|RECORD=41|IndexInSheet=72|OwnerPartId=-1|Color=8388608|FontID=1|IsHidden=T|Text=Time Card|Name=Title|ReadOnlyState=1
|RECORD=41|IndexInSheet=73|OwnerPartId=-1|Color=8388608|FontID=1|IsHidden=T|Text=*|Name=DocumentNumber|ReadOnlyState=1
|RECORD=41|IndexInSheet=74|OwnerPartId=-1|Color=8388608|FontID=1|IsHidden=T|Text=*|Name=Revision|ReadOnlyState=1
|RECORD=41|IndexInSheet=75|OwnerPartId=-1|Color=8388608|FontID=1|IsHidden=T|Text=2|Name=SheetNumber|ReadOnlyState=1
|RECORD=41|IndexInSheet=76|OwnerPartId=-1|Color=8388608|FontID=1|IsHidden=T|Text=8|Name=SheetTotal|ReadOnlyState=1
|RECORD=41|IndexInSheet=77|OwnerPartId=-1|Color=8388608|FontID=1|IsHidden=T|Text=*|Name=Rule|ReadOnlyState=1
|RECORD=41|IndexInSheet=78|OwnerPartId=-1|Color=8388608|FontID=1|IsHidden=T|Text=*|Name=ImagePath|ReadOnlyState=1
|RECORD=41|IndexInSheet=79|OwnerPartId=-1|Color=8388608|FontID=1|IsHidden=T|Text=*|Name=ProjectName|ReadOnlyState=1
|RECORD=41|IndexInSheet=80|OwnerPartId=-1|Color=8388608|FontID=1|IsHidden=T|Text=*|Name=Application_BuildNumber|ReadOnlyState=1
|RECORD=41|IndexInSheet=81|OwnerPartId=-1|Color=8388608|FontID=1|IsHidden=T|Name=SheetSymbolDesignator|ReadOnlyState=1
|RECORD=41|IndexInSheet=82|OwnerPartId=-1|Color=8388608|FontID=1|IsHidden=T|Name=VersionControl_RevNumberShort|ReadOnlyState=1
|RECORD=41|IndexInSheet=83|OwnerPartId=-1|Color=8388608|FontID=1|IsHidden=T|Name=VersionControl_ProjFolderRevNumberShort|ReadOnlyState=1
|RECORD=41|IndexInSheet=84|OwnerPartId=-1|Location.X=839|Location.Y=9|Color=8388608|FontID=1|IsHidden=T|Text=*|Name=Title2
|RECORD=41|IndexInSheet=85|OwnerPartId=-1|Location.Y=-10|Color=8388608|FontID=1|IsHidden=T|Text=*|Name=Project
|RECORD=41|IndexInSheet=86|OwnerPartId=-1|Location.Y=-10|Color=8388608|FontID=1|IsHidden=T|Text=--/--/--|Name=ENG_APP_DATE
|RECORD=41|IndexInSheet=87|OwnerPartId=-1|Location.Y=-10|Color=8388608|FontID=1|IsHidden=T|Text=--/--/--|Name=DSN_APP_DATE
|RECORD=41|IndexInSheet=88|OwnerPartId=-1|Location.Y=-10|Color=8388608|FontID=1|IsHidden=T|Text=--/--/--|Name=CHK_APP_DATE
|RECORD=1|LibReference=8706943c75ba83719d021d2fdc84c58|ComponentDescription=LED GREEN CLEAR SMD|PartCount=2|DisplayModeCount=1|IndexInSheet=89|OwnerPartId=-1|Location.X=580|Location.Y=800|Orientation=3|CurrentPartId=1|LibraryPath=*|SourceLibraryName=Altium Content Vault|TargetFileName=*|AreaColor=11599871|Color=128|PartIDLocked=T|DesignItemId=CMP-2000-05198-2|AllPinCount=2
|RECORD=2|OwnerIndex=879|OwnerPartId=1|Electrical=4|PinConglomerate=49|PinLength=20|Location.X=580|Location.Y=780|Name=A|Designator=2|PinPropagationDelay=0.000000E+000
|RECORD=2|OwnerIndex=879|OwnerPartId=1|Electrical=4|PinConglomerate=51|PinLength=20|Location.X=580|Location.Y=760|Name=C|Designator=1|PinPropagationDelay=0.000000E+000
|RECORD=13|OwnerIndex=879|IsNotAccesible=T|IndexInSheet=2|OwnerPartId=1|Location.X=590|Location.Y=780|Corner.X=570|Corner.Y=780|LineWidth=1|Color=16711680
|RECORD=13|OwnerIndex=879|IsNotAccesible=T|IndexInSheet=3|OwnerPartId=1|Location.X=590|Location.Y=760|Corner.X=570|Corner.Y=760|LineWidth=1|Color=16711680
|RECORD=13|OwnerIndex=879|IsNotAccesible=T|IndexInSheet=4|OwnerPartId=1|Location.X=590|Location.Y=780|Corner.X=580|Corner.Y=760|LineWidth=1|Color=16711680
|RECORD=13|OwnerIndex=879|IsNotAccesible=T|IndexInSheet=5|OwnerPartId=1|Location.X=570|Location.Y=780|Corner.X=580|Corner.Y=760|LineWidth=1|Color=16711680
|RECORD=13|OwnerIndex=879|IsNotAccesible=T|IndexInSheet=6|OwnerPartId=1|Location.X=592|Location.Y=775|Corner.X=602|Corner.Y=765|LineWidth=1|Color=16711680
|RECORD=13|OwnerIndex=879|IsNotAccesible=T|IndexInSheet=7|OwnerPartId=1|Location.X=602|Location.Y=765|Corner.X=602|Corner.Y=770|LineWidth=1|Color=16711680
|RECORD=13|OwnerIndex=879|IsNotAccesible=T|IndexInSheet=8|OwnerPartId=1|Location.X=602|Location.Y=765|Corner.X=597|Corner.Y=765|LineWidth=1|Color=16711680
|RECORD=13|OwnerIndex=879|IsNotAccesible=T|IndexInSheet=9|OwnerPartId=1|Location.X=588|Location.Y=768|Corner.X=598|Corner.Y=758|LineWidth=1|Color=16711680
|RECORD=13|OwnerIndex=879|IsNotAccesible=T|IndexInSheet=10|OwnerPartId=1|Location.X=598|Location.Y=758|Corner.X=598|Corner.Y=763|LineWidth=1|Color=16711680
|RECORD=13|OwnerIndex=879|IsNotAccesible=T|IndexInSheet=11|OwnerPartId=1|Location.X=598|Location.Y=758|Corner.X=593|Corner.Y=758|LineWidth=1|Color=16711680
|RECORD=13|OwnerIndex=879|IsNotAccesible=T|IndexInSheet=12|OwnerPartId=1|Location.X=580|Location.Y=780|Corner.X=580|Corner.Y=783|LineWidth=1|Color=16711680
|RECORD=13|OwnerIndex=879|IsNotAccesible=T|IndexInSheet=13|OwnerPartId=1|Location.X=580|Location.Y=760|Corner.X=580|Corner.Y=757|LineWidth=1|Color=16711680
|RECORD=41|OwnerIndex=879|IndexInSheet=14|OwnerPartId=-1|Location.X=569|Location.Y=802|Color=8388608|FontID=1|IsHidden=T|Text=0.8mm|Name=Width
|RECORD=41|OwnerIndex=879|IndexInSheet=15|OwnerPartId=-1|Location.X=569|Location.Y=802|Color=8388608|FontID=1|IsHidden=T|Text=0603|Name=Case Code (Imperial)
|RECORD=41|OwnerIndex=879|IndexInSheet=16|OwnerPartId=-1|Location.X=569|Location.Y=802|Color=8388608|FontID=1|IsHidden=T|Text=2|Name=Number of Pins
|RECORD=41|OwnerIndex=879|IndexInSheet=17|OwnerPartId=-1|Location.X=569|Location.Y=802|Color=8388608|FontID=1|IsHidden=T|Text=75mW|Name=Max Power Dissipation
|RECORD=41|OwnerIndex=879|IndexInSheet=18|OwnerPartId=-1|Location.X=569|Location.Y=802|Color=8388608|FontID=1|IsHidden=T|Text=30mA|Name=Forward Current
|RECORD=41|OwnerIndex=879|IndexInSheet=19|OwnerPartId=-1|Location.X=569|Location.Y=802|Color=8388608|FontID=1|IsHidden=T|Text=Lead Free|Name=Lead Free
|RECORD=41|OwnerIndex=879|IndexInSheet=20|OwnerPartId=-1|Location.X=569|Location.Y=802|Color=8388608|FontID=1|IsHidden=T|Text=5V|Name=Reverse Voltage
|RECORD=41|OwnerIndex=879|IndexInSheet=21|OwnerPartId=-1|Location.X=569|Location.Y=802|Color=8388608|FontID=1|IsHidden=T|Text=Colorless|Name=Lens Color
|RECORD=41|OwnerIndex=879|IndexInSheet=22|OwnerPartId=-1|Location.X=569|Location.Y=802|Color=8388608|FontID=1|IsHidden=T|Text=2V|Name=Forward Voltage
|RECORD=41|OwnerIndex=879|IndexInSheet=23|OwnerPartId=-1|Location.X=569|Location.Y=802|Color=8388608|FontID=1|IsHidden=T|Text=Tape and Reel|Name=Packaging
|RECORD=41|OwnerIndex=879|IndexInSheet=24|OwnerPartId=-1|Location.X=569|Location.Y=802|Color=8388608|FontID=1|IsHidden=T|Text=1|Name=Package Quantity
|RECORD=41|OwnerIndex=879|IndexInSheet=25|OwnerPartId=-1|Location.X=569|Location.Y=802|Color=8388608|FontID=1|IsHidden=T|Text=-55°C|Name=Min Operating Temperature
|RECORD=41|OwnerIndex=879|IndexInSheet=26|OwnerPartId=-1|Location.X=569|Location.Y=802|Color=8388608|FontID=1|IsHidden=T|Text=0603|Name=Case/Package
|RECORD=41|OwnerIndex=879|IndexInSheet=27|OwnerPartId=-1|Location.X=569|Location.Y=802|Color=8388608|FontID=1|IsHidden=T|Text=1.6mm|Name=Length
|RECORD=41|OwnerIndex=879|IndexInSheet=28|OwnerPartId=-1|Location.X=569|Location.Y=802|Color=8388608|FontID=1|IsHidden=T|Text=75mW|Name=Power Dissipation
|RECORD=41|OwnerIndex=879|IndexInSheet=29|OwnerPartId=-1|Location.X=569|Location.Y=802|Color=8388608|FontID=1|IsHidden=T|Text=571nm|Name=Dominant Wavelength
|RECORD=41|OwnerIndex=879|IndexInSheet=30|OwnerPartId=-1|Location.X=569|Location.Y=802|Color=8388608|FontID=1|IsHidden=T|Text=0.8mm|Name=Depth
|RECORD=41|OwnerIndex=879|IndexInSheet=31|OwnerPartId=-1|Location.X=569|Location.Y=802|Color=8388608|FontID=1|IsHidden=T|Text=No|Name=Radiation Hardening
|RECORD=41|OwnerIndex=879|IndexInSheet=32|OwnerPartId=-1|Location.X=569|Location.Y=802|Color=8388608|FontID=1|IsHidden=T|Text=Surface Mount|Name=Mount
|RECORD=41|OwnerIndex=879|IndexInSheet=33|OwnerPartId=-1|Location.X=569|Location.Y=802|Color=8388608|FontID=1|IsHidden=T|Text=85°C|Name=Max Operating Temperature
|RECORD=41|OwnerIndex=879|IndexInSheet=34|OwnerPartId=-1|Location.X=569|Location.Y=802|Color=8388608|FontID=1|IsHidden=T|Text=Green|Name=Color
|RECORD=41|OwnerIndex=879|IndexInSheet=35|OwnerPartId=-1|Location.X=569|Location.Y=802|Color=8388608|FontID=1|IsHidden=T|Text=75mW|Name=Power Rating
|RECORD=41|OwnerIndex=879|IndexInSheet=36|OwnerPartId=-1|Location.X=569|Location.Y=802|Color=8388608|FontID=1|IsHidden=T|Text=0.55mm|Name=Height
|RECORD=41|OwnerIndex=879|IndexInSheet=37|OwnerPartId=-1|Location.X=569|Location.Y=802|Color=8388608|FontID=1|IsHidden=T|Text=1|Name=Number of LEDs
|RECORD=41|OwnerIndex=879|IndexInSheet=38|OwnerPartId=-1|Location.X=569|Location.Y=802|Color=8388608|FontID=1|IsHidden=T|Text=130°|Name=Viewing Angle
|RECORD=41|OwnerIndex=879|IndexInSheet=39|OwnerPartId=-1|Location.X=569|Location.Y=802|Color=8388608|FontID=1|IsHidden=T|Text=Rectangular|Name=Lens Style
|RECORD=41|OwnerIndex=879|IndexInSheet=40|OwnerPartId=-1|Location.X=569|Location.Y=802|Color=8388608|FontID=1|IsHidden=T|Text=Green|Name=Illumination Color
|RECORD=41|OwnerIndex=879|IndexInSheet=41|OwnerPartId=-1|Location.X=569|Location.Y=802|Color=8388608|FontID=1|IsHidden=T|Text=20mA|Name=Test Current
|RECORD=41|OwnerIndex=879|IndexInSheet=42|OwnerPartId=-1|Location.X=569|Location.Y=802|Color=8388608|FontID=1|IsHidden=T|Text=1608|Name=Case Code (Metric)
|RECORD=41|OwnerIndex=879|IndexInSheet=43|OwnerPartId=-1|Location.X=569|Location.Y=802|Color=8388608|FontID=1|IsHidden=T|Text=Clear|Name=Lens Transparency
|RECORD=41|OwnerIndex=879|IndexInSheet=44|OwnerPartId=-1|Location.X=569|Location.Y=802|Color=8388608|FontID=1|IsHidden=T|Text=35mcd|Name=Luminous Intensity
|RECORD=41|OwnerIndex=879|IndexInSheet=45|OwnerPartId=-1|Location.X=569|Location.Y=802|Color=8388608|FontID=1|IsHidden=T|Text=1|Name=Number of Elements
|RECORD=41|OwnerIndex=879|IndexInSheet=46|OwnerPartId=-1|Location.X=569|Location.Y=802|Color=8388608|FontID=1|IsHidden=T|Text=574nm|Name=Wavelength
|RECORD=34|OwnerIndex=879|IndexInSheet=-1|OwnerPartId=-1|Location.X=565|Location.Y=760|Orientation=1|Color=8388608|FontID=2|Text=D3|Name=Designator|ReadOnlyState=1
|RECORD=41|OwnerIndex=879|IndexInSheet=-1|OwnerPartId=1|Location.X=619|Location.Y=740|Orientation=1|Color=8388608|FontID=2|Text=LTST-C191KGKT|Name=Comment
|RECORD=44|OwnerIndex=879
|RECORD=45|OwnerIndex=931|IndexInSheet=-1|UseComponentLibrary=T|ModelName=FP-LTST-C191KGKT-MFG|ModelType=PCBLIB|DatafileCount=1|ModelDatafileEntity0=FP-LTST-C191KGKT-MFG|ModelDatafileKind0=PCBLib|IsCurrent=T|DatalinksLocked=T|DatabaseDatalinksLocked=T
|RECORD=46|OwnerIndex=932
|RECORD=48|OwnerIndex=932
|RECORD=1|LibReference=8706943c75ba83719d021d2fdc84c58|ComponentDescription=LED GREEN CLEAR SMD|PartCount=2|DisplayModeCount=1|IndexInSheet=90|OwnerPartId=-1|Location.X=680|Location.Y=800|Orientation=3|CurrentPartId=1|LibraryPath=*|SourceLibraryName=Altium Content Vault|TargetFileName=*|AreaColor=11599871|Color=128|PartIDLocked=T|DesignItemId=CMP-2000-05198-2|AllPinCount=2
|RECORD=2|OwnerIndex=935|OwnerPartId=1|Electrical=4|PinConglomerate=49|PinLength=20|Location.X=680|Location.Y=780|Name=A|Designator=2|PinPropagationDelay=0.000000E+000
|RECORD=2|OwnerIndex=935|OwnerPartId=1|Electrical=4|PinConglomerate=51|PinLength=20|Location.X=680|Location.Y=760|Name=C|Designator=1|PinPropagationDelay=0.000000E+000
|RECORD=13|OwnerIndex=935|IsNotAccesible=T|IndexInSheet=2|OwnerPartId=1|Location.X=690|Location.Y=780|Corner.X=670|Corner.Y=780|LineWidth=1|Color=16711680
|RECORD=13|OwnerIndex=935|IsNotAccesible=T|IndexInSheet=3|OwnerPartId=1|Location.X=690|Location.Y=760|Corner.X=670|Corner.Y=760|LineWidth=1|Color=16711680
|RECORD=13|OwnerIndex=935|IsNotAccesible=T|IndexInSheet=4|OwnerPartId=1|Location.X=690|Location.Y=780|Corner.X=680|Corner.Y=760|LineWidth=1|Color=16711680
|RECORD=13|OwnerIndex=935|IsNotAccesible=T|IndexInSheet=5|OwnerPartId=1|Location.X=670|Location.Y=780|Corner.X=680|Corner.Y=760|LineWidth=1|Color=16711680
|RECORD=13|OwnerIndex=935|IsNotAccesible=T|IndexInSheet=6|OwnerPartId=1|Location.X=692|Location.Y=775|Corner.X=702|Corner.Y=765|LineWidth=1|Color=16711680
|RECORD=13|OwnerIndex=935|IsNotAccesible=T|IndexInSheet=7|OwnerPartId=1|Location.X=702|Location.Y=765|Corner.X=702|Corner.Y=770|LineWidth=1|Color=16711680
|RECORD=13|OwnerIndex=935|IsNotAccesible=T|IndexInSheet=8|OwnerPartId=1|Location.X=702|Location.Y=765|Corner.X=697|Corner.Y=765|LineWidth=1|Color=16711680
|RECORD=13|OwnerIndex=935|IsNotAccesible=T|IndexInSheet=9|OwnerPartId=1|Location.X=688|Location.Y=768|Corner.X=698|Corner.Y=758|LineWidth=1|Color=16711680
|RECORD=13|OwnerIndex=935|IsNotAccesible=T|IndexInSheet=10|OwnerPartId=1|Location.X=698|Location.Y=758|Corner.X=698|Corner.Y=763|LineWidth=1|Color=16711680
|RECORD=13|OwnerIndex=935|IsNotAccesible=T|IndexInSheet=11|OwnerPartId=1|Location.X=698|Location.Y=758|Corner.X=693|Corner.Y=758|LineWidth=1|Color=16711680
|RECORD=13|OwnerIndex=935|IsNotAccesible=T|IndexInSheet=12|OwnerPartId=1|Location.X=680|Location.Y=780|Corner.X=680|Corner.Y=783|LineWidth=1|Color=16711680
|RECORD=13|OwnerIndex=935|IsNotAccesible=T|IndexInSheet=13|OwnerPartId=1|Location.X=680|Location.Y=760|Corner.X=680|Corner.Y=757|LineWidth=1|Color=16711680
|RECORD=41|OwnerIndex=935|IndexInSheet=14|OwnerPartId=-1|Location.X=669|Location.Y=802|Color=8388608|FontID=1|IsHidden=T|Text=0.8mm|Name=Width
|RECORD=41|OwnerIndex=935|IndexInSheet=15|OwnerPartId=-1|Location.X=669|Location.Y=802|Color=8388608|FontID=1|IsHidden=T|Text=0603|Name=Case Code (Imperial)
|RECORD=41|OwnerIndex=935|IndexInSheet=16|OwnerPartId=-1|Location.X=669|Location.Y=802|Color=8388608|FontID=1|IsHidden=T|Text=2|Name=Number of Pins
|RECORD=41|OwnerIndex=935|IndexInSheet=17|OwnerPartId=-1|Location.X=669|Location.Y=802|Color=8388608|FontID=1|IsHidden=T|Text=75mW|Name=Max Power Dissipation
|RECORD=41|OwnerIndex=935|IndexInSheet=18|OwnerPartId=-1|Location.X=669|Location.Y=802|Color=8388608|FontID=1|IsHidden=T|Text=30mA|Name=Forward Current
|RECORD=41|OwnerIndex=935|IndexInSheet=19|OwnerPartId=-1|Location.X=669|Location.Y=802|Color=8388608|FontID=1|IsHidden=T|Text=Lead Free|Name=Lead Free
|RECORD=41|OwnerIndex=935|IndexInSheet=20|OwnerPartId=-1|Location.X=669|Location.Y=802|Color=8388608|FontID=1|IsHidden=T|Text=5V|Name=Reverse Voltage
|RECORD=41|OwnerIndex=935|IndexInSheet=21|OwnerPartId=-1|Location.X=669|Location.Y=802|Color=8388608|FontID=1|IsHidden=T|Text=Colorless|Name=Lens Color
|RECORD=41|OwnerIndex=935|IndexInSheet=22|OwnerPartId=-1|Location.X=669|Location.Y=802|Color=8388608|FontID=1|IsHidden=T|Text=2V|Name=Forward Voltage
|RECORD=41|OwnerIndex=935|IndexInSheet=23|OwnerPartId=-1|Location.X=669|Location.Y=802|Color=8388608|FontID=1|IsHidden=T|Text=Tape and Reel|Name=Packaging
|RECORD=41|OwnerIndex=935|IndexInSheet=24|OwnerPartId=-1|Location.X=669|Location.Y=802|Color=8388608|FontID=1|IsHidden=T|Text=1|Name=Package Quantity
|RECORD=41|OwnerIndex=935|IndexInSheet=25|OwnerPartId=-1|Location.X=669|Location.Y=802|Color=8388608|FontID=1|IsHidden=T|Text=-55°C|Name=Min Operating Temperature
|RECORD=41|OwnerIndex=935|IndexInSheet=26|OwnerPartId=-1|Location.X=669|Location.Y=802|Color=8388608|FontID=1|IsHidden=T|Text=0603|Name=Case/Package
|RECORD=41|OwnerIndex=935|IndexInSheet=27|OwnerPartId=-1|Location.X=669|Location.Y=802|Color=8388608|FontID=1|IsHidden=T|Text=1.6mm|Name=Length
|RECORD=41|OwnerIndex=935|IndexInSheet=28|OwnerPartId=-1|Location.X=669|Location.Y=802|Color=8388608|FontID=1|IsHidden=T|Text=75mW|Name=Power Dissipation
|RECORD=41|OwnerIndex=935|IndexInSheet=29|OwnerPartId=-1|Location.X=669|Location.Y=802|Color=8388608|FontID=1|IsHidden=T|Text=571nm|Name=Dominant Wavelength
|RECORD=41|OwnerIndex=935|IndexInSheet=30|OwnerPartId=-1|Location.X=669|Location.Y=802|Color=8388608|FontID=1|IsHidden=T|Text=0.8mm|Name=Depth
|RECORD=41|OwnerIndex=935|IndexInSheet=31|OwnerPartId=-1|Location.X=669|Location.Y=802|Color=8388608|FontID=1|IsHidden=T|Text=No|Name=Radiation Hardening
|RECORD=41|OwnerIndex=935|IndexInSheet=32|OwnerPartId=-1|Location.X=669|Location.Y=802|Color=8388608|FontID=1|IsHidden=T|Text=Surface Mount|Name=Mount
|RECORD=41|OwnerIndex=935|IndexInSheet=33|OwnerPartId=-1|Location.X=669|Location.Y=802|Color=8388608|FontID=1|IsHidden=T|Text=85°C|Name=Max Operating Temperature
|RECORD=41|OwnerIndex=935|IndexInSheet=34|OwnerPartId=-1|Location.X=669|Location.Y=802|Color=8388608|FontID=1|IsHidden=T|Text=Green|Name=Color
|RECORD=41|OwnerIndex=935|IndexInSheet=35|OwnerPartId=-1|Location.X=669|Location.Y=802|Color=8388608|FontID=1|IsHidden=T|Text=75mW|Name=Power Rating
|RECORD=41|OwnerIndex=935|IndexInSheet=36|OwnerPartId=-1|Location.X=669|Location.Y=802|Color=8388608|FontID=1|IsHidden=T|Text=0.55mm|Name=Height
|RECORD=41|OwnerIndex=935|IndexInSheet=37|OwnerPartId=-1|Location.X=669|Location.Y=802|Color=8388608|FontID=1|IsHidden=T|Text=1|Name=Number of LEDs
|RECORD=41|OwnerIndex=935|IndexInSheet=38|OwnerPartId=-1|Location.X=669|Location.Y=802|Color=8388608|FontID=1|IsHidden=T|Text=130°|Name=Viewing Angle
|RECORD=41|OwnerIndex=935|IndexInSheet=39|OwnerPartId=-1|Location.X=669|Location.Y=802|Color=8388608|FontID=1|IsHidden=T|Text=Rectangular|Name=Lens Style
|RECORD=41|OwnerIndex=935|IndexInSheet=40|OwnerPartId=-1|Location.X=669|Location.Y=802|Color=8388608|FontID=1|IsHidden=T|Text=Green|Name=Illumination Color
|RECORD=41|OwnerIndex=935|IndexInSheet=41|OwnerPartId=-1|Location.X=669|Location.Y=802|Color=8388608|FontID=1|IsHidden=T|Text=20mA|Name=Test Current
|RECORD=41|OwnerIndex=935|IndexInSheet=42|OwnerPartId=-1|Location.X=669|Location.Y=802|Color=8388608|FontID=1|IsHidden=T|Text=1608|Name=Case Code (Metric)
|RECORD=41|OwnerIndex=935|IndexInSheet=43|OwnerPartId=-1|Location.X=669|Location.Y=802|Color=8388608|FontID=1|IsHidden=T|Text=Clear|Name=Lens Transparency
|RECORD=41|OwnerIndex=935|IndexInSheet=44|OwnerPartId=-1|Location.X=669|Location.Y=802|Color=8388608|FontID=1|IsHidden=T|Text=35mcd|Name=Luminous Intensity
|RECORD=41|OwnerIndex=935|IndexInSheet=45|OwnerPartId=-1|Location.X=669|Location.Y=802|Color=8388608|FontID=1|IsHidden=T|Text=1|Name=Number of Elements
|RECORD=41|OwnerIndex=935|IndexInSheet=46|OwnerPartId=-1|Location.X=669|Location.Y=802|Color=8388608|FontID=1|IsHidden=T|Text=574nm|Name=Wavelength
|RECORD=34|OwnerIndex=935|IndexInSheet=-1|OwnerPartId=-1|Location.X=665|Location.Y=760|Orientation=1|Color=8388608|FontID=2|Text=D9|Name=Designator|ReadOnlyState=1
|RECORD=41|OwnerIndex=935|IndexInSheet=-1|OwnerPartId=1|Location.X=719|Location.Y=740|Orientation=1|Color=8388608|FontID=2|Text=LTST-C191KGKT|Name=Comment
|RECORD=44|OwnerIndex=935
|RECORD=45|OwnerIndex=987|IndexInSheet=-1|UseComponentLibrary=T|ModelName=FP-LTST-C191KGKT-MFG|ModelType=PCBLIB|DatafileCount=1|ModelDatafileEntity0=FP-LTST-C191KGKT-MFG|ModelDatafileKind0=PCBLib|IsCurrent=T|DatalinksLocked=T|DatabaseDatalinksLocked=T
|RECORD=46|OwnerIndex=988
|RECORD=48|OwnerIndex=988
|RECORD=1|LibReference=8706943c75ba83719d021d2fdc84c58|ComponentDescription=LED GREEN CLEAR SMD|PartCount=2|DisplayModeCount=1|IndexInSheet=91|OwnerPartId=-1|Location.X=780|Location.Y=800|Orientation=3|CurrentPartId=1|LibraryPath=*|SourceLibraryName=Altium Content Vault|TargetFileName=*|AreaColor=11599871|Color=128|PartIDLocked=T|DesignItemId=CMP-2000-05198-2|AllPinCount=2
|RECORD=2|OwnerIndex=991|OwnerPartId=1|Electrical=4|PinConglomerate=49|PinLength=20|Location.X=780|Location.Y=780|Name=A|Designator=2|PinPropagationDelay=0.000000E+000
|RECORD=2|OwnerIndex=991|OwnerPartId=1|Electrical=4|PinConglomerate=51|PinLength=20|Location.X=780|Location.Y=760|Name=C|Designator=1|PinPropagationDelay=0.000000E+000
|RECORD=13|OwnerIndex=991|IsNotAccesible=T|IndexInSheet=2|OwnerPartId=1|Location.X=790|Location.Y=780|Corner.X=770|Corner.Y=780|LineWidth=1|Color=16711680
|RECORD=13|OwnerIndex=991|IsNotAccesible=T|IndexInSheet=3|OwnerPartId=1|Location.X=790|Location.Y=760|Corner.X=770|Corner.Y=760|LineWidth=1|Color=16711680
|RECORD=13|OwnerIndex=991|IsNotAccesible=T|IndexInSheet=4|OwnerPartId=1|Location.X=790|Location.Y=780|Corner.X=780|Corner.Y=760|LineWidth=1|Color=16711680
|RECORD=13|OwnerIndex=991|IsNotAccesible=T|IndexInSheet=5|OwnerPartId=1|Location.X=770|Location.Y=780|Corner.X=780|Corner.Y=760|LineWidth=1|Color=16711680
|RECORD=13|OwnerIndex=991|IsNotAccesible=T|IndexInSheet=6|OwnerPartId=1|Location.X=792|Location.Y=775|Corner.X=802|Corner.Y=765|LineWidth=1|Color=16711680
|RECORD=13|OwnerIndex=991|IsNotAccesible=T|IndexInSheet=7|OwnerPartId=1|Location.X=802|Location.Y=765|Corner.X=802|Corner.Y=770|LineWidth=1|Color=16711680
|RECORD=13|OwnerIndex=991|IsNotAccesible=T|IndexInSheet=8|OwnerPartId=1|Location.X=802|Location.Y=765|Corner.X=797|Corner.Y=765|LineWidth=1|Color=16711680
|RECORD=13|OwnerIndex=991|IsNotAccesible=T|IndexInSheet=9|OwnerPartId=1|Location.X=788|Location.Y=768|Corner.X=798|Corner.Y=758|LineWidth=1|Color=16711680
|RECORD=13|OwnerIndex=991|IsNotAccesible=T|IndexInSheet=10|OwnerPartId=1|Location.X=798|Location.Y=758|Corner.X=798|Corner.Y=763|LineWidth=1|Color=16711680
|RECORD=13|OwnerIndex=991|IsNotAccesible=T|IndexInSheet=11|OwnerPartId=1|Location.X=798|Location.Y=758|Corner.X=793|Corner.Y=758|LineWidth=1|Color=16711680
|RECORD=13|OwnerIndex=991|IsNotAccesible=T|IndexInSheet=12|OwnerPartId=1|Location.X=780|Location.Y=780|Corner.X=780|Corner.Y=783|LineWidth=1|Color=16711680
|RECORD=13|OwnerIndex=991|IsNotAccesible=T|IndexInSheet=13|OwnerPartId=1|Location.X=780|Location.Y=760|Corner.X=780|Corner.Y=757|LineWidth=1|Color=16711680
|RECORD=41|OwnerIndex=991|IndexInSheet=14|OwnerPartId=-1|Location.X=769|Location.Y=802|Color=8388608|FontID=1|IsHidden=T|Text=0.8mm|Name=Width
|RECORD=41|OwnerIndex=991|IndexInSheet=15|OwnerPartId=-1|Location.X=769|Location.Y=802|Color=8388608|FontID=1|IsHidden=T|Text=0603|Name=Case Code (Imperial)
|RECORD=41|OwnerIndex=991|IndexInSheet=16|OwnerPartId=-1|Location.X=769|Location.Y=802|Color=8388608|FontID=1|IsHidden=T|Text=2|Name=Number of Pins
|RECORD=41|OwnerIndex=991|IndexInSheet=17|OwnerPartId=-1|Location.X=769|Location.Y=802|Color=8388608|FontID=1|IsHidden=T|Text=75mW|Name=Max Power Dissipation
|RECORD=41|OwnerIndex=991|IndexInSheet=18|OwnerPartId=-1|Location.X=769|Location.Y=802|Color=8388608|FontID=1|IsHidden=T|Text=30mA|Name=Forward Current
|RECORD=41|OwnerIndex=991|IndexInSheet=19|OwnerPartId=-1|Location.X=769|Location.Y=802|Color=8388608|FontID=1|IsHidden=T|Text=Lead Free|Name=Lead Free
|RECORD=41|OwnerIndex=991|IndexInSheet=20|OwnerPartId=-1|Location.X=769|Location.Y=802|Color=8388608|FontID=1|IsHidden=T|Text=5V|Name=Reverse Voltage
|RECORD=41|OwnerIndex=991|IndexInSheet=21|OwnerPartId=-1|Location.X=769|Location.Y=802|Color=8388608|FontID=1|IsHidden=T|Text=Colorless|Name=Lens Color
|RECORD=41|OwnerIndex=991|IndexInSheet=22|OwnerPartId=-1|Location.X=769|Location.Y=802|Color=8388608|FontID=1|IsHidden=T|Text=2V|Name=Forward Voltage
|RECORD=41|OwnerIndex=991|IndexInSheet=23|OwnerPartId=-1|Location.X=769|Location.Y=802|Color=8388608|FontID=1|IsHidden=T|Text=Tape and Reel|Name=Packaging
|RECORD=41|OwnerIndex=991|IndexInSheet=24|OwnerPartId=-1|Location.X=769|Location.Y=802|Color=8388608|FontID=1|IsHidden=T|Text=1|Name=Package Quantity
|RECORD=41|OwnerIndex=991|IndexInSheet=25|OwnerPartId=-1|Location.X=769|Location.Y=802|Color=8388608|FontID=1|IsHidden=T|Text=-55°C|Name=Min Operating Temperature
|RECORD=41|OwnerIndex=991|IndexInSheet=26|OwnerPartId=-1|Location.X=769|Location.Y=802|Color=8388608|FontID=1|IsHidden=T|Text=0603|Name=Case/Package
|RECORD=41|OwnerIndex=991|IndexInSheet=27|OwnerPartId=-1|Location.X=769|Location.Y=802|Color=8388608|FontID=1|IsHidden=T|Text=1.6mm|Name=Length
|RECORD=41|OwnerIndex=991|IndexInSheet=28|OwnerPartId=-1|Location.X=769|Location.Y=802|Color=8388608|FontID=1|IsHidden=T|Text=75mW|Name=Power Dissipation
|RECORD=41|OwnerIndex=991|IndexInSheet=29|OwnerPartId=-1|Location.X=769|Location.Y=802|Color=8388608|FontID=1|IsHidden=T|Text=571nm|Name=Dominant Wavelength
|RECORD=41|OwnerIndex=991|IndexInSheet=30|OwnerPartId=-1|Location.X=769|Location.Y=802|Color=8388608|FontID=1|IsHidden=T|Text=0.8mm|Name=Depth
|RECORD=41|OwnerIndex=991|IndexInSheet=31|OwnerPartId=-1|Location.X=769|Location.Y=802|Color=8388608|FontID=1|IsHidden=T|Text=No|Name=Radiation Hardening
|RECORD=41|OwnerIndex=991|IndexInSheet=32|OwnerPartId=-1|Location.X=769|Location.Y=802|Color=8388608|FontID=1|IsHidden=T|Text=Surface Mount|Name=Mount
|RECORD=41|OwnerIndex=991|IndexInSheet=33|OwnerPartId=-1|Location.X=769|Location.Y=802|Color=8388608|FontID=1|IsHidden=T|Text=85°C|Name=Max Operating Temperature
|RECORD=41|OwnerIndex=991|IndexInSheet=34|OwnerPartId=-1|Location.X=769|Location.Y=802|Color=8388608|FontID=1|IsHidden=T|Text=Green|Name=Color
|RECORD=41|OwnerIndex=991|IndexInSheet=35|OwnerPartId=-1|Location.X=769|Location.Y=802|Color=8388608|FontID=1|IsHidden=T|Text=75mW|Name=Power Rating
|RECORD=41|OwnerIndex=991|IndexInSheet=36|OwnerPartId=-1|Location.X=769|Location.Y=802|Color=8388608|FontID=1|IsHidden=T|Text=0.55mm|Name=Height
|RECORD=41|OwnerIndex=991|IndexInSheet=37|OwnerPartId=-1|Location.X=769|Location.Y=802|Color=8388608|FontID=1|IsHidden=T|Text=1|Name=Number of LEDs
|RECORD=41|OwnerIndex=991|IndexInSheet=38|OwnerPartId=-1|Location.X=769|Location.Y=802|Color=8388608|FontID=1|IsHidden=T|Text=130°|Name=Viewing Angle
|RECORD=41|OwnerIndex=991|IndexInSheet=39|OwnerPartId=-1|Location.X=769|Location.Y=802|Color=8388608|FontID=1|IsHidden=T|Text=Rectangular|Name=Lens Style
|RECORD=41|OwnerIndex=991|IndexInSheet=40|OwnerPartId=-1|Location.X=769|Location.Y=802|Color=8388608|FontID=1|IsHidden=T|Text=Green|Name=Illumination Color
|RECORD=41|OwnerIndex=991|IndexInSheet=41|OwnerPartId=-1|Location.X=769|Location.Y=802|Color=8388608|FontID=1|IsHidden=T|Text=20mA|Name=Test Current
|RECORD=41|OwnerIndex=991|IndexInSheet=42|OwnerPartId=-1|Location.X=769|Location.Y=802|Color=8388608|FontID=1|IsHidden=T|Text=1608|Name=Case Code (Metric)
|RECORD=41|OwnerIndex=991|IndexInSheet=43|OwnerPartId=-1|Location.X=769|Location.Y=802|Color=8388608|FontID=1|IsHidden=T|Text=Clear|Name=Lens Transparency
|RECORD=41|OwnerIndex=991|IndexInSheet=44|OwnerPartId=-1|Location.X=769|Location.Y=802|Color=8388608|FontID=1|IsHidden=T|Text=35mcd|Name=Luminous Intensity
|RECORD=41|OwnerIndex=991|IndexInSheet=45|OwnerPartId=-1|Location.X=769|Location.Y=802|Color=8388608|FontID=1|IsHidden=T|Text=1|Name=Number of Elements
|RECORD=41|OwnerIndex=991|IndexInSheet=46|OwnerPartId=-1|Location.X=769|Location.Y=802|Color=8388608|FontID=1|IsHidden=T|Text=574nm|Name=Wavelength
|RECORD=34|OwnerIndex=991|IndexInSheet=-1|OwnerPartId=-1|Location.X=765|Location.Y=760|Orientation=1|Color=8388608|FontID=2|Text=D10|Name=Designator|ReadOnlyState=1
|RECORD=41|OwnerIndex=991|IndexInSheet=-1|OwnerPartId=1|Location.X=819|Location.Y=740|Orientation=1|Color=8388608|FontID=2|Text=LTST-C191KGKT|Name=Comment
|RECORD=44|OwnerIndex=991
|RECORD=45|OwnerIndex=1043|IndexInSheet=-1|UseComponentLibrary=T|ModelName=FP-LTST-C191KGKT-MFG|ModelType=PCBLIB|DatafileCount=1|ModelDatafileEntity0=FP-LTST-C191KGKT-MFG|ModelDatafileKind0=PCBLib|IsCurrent=T|DatalinksLocked=T|DatabaseDatalinksLocked=T
|RECORD=46|OwnerIndex=1044
|RECORD=48|OwnerIndex=1044
|RECORD=1|LibReference=8706943c75ba83719d021d2fdc84c58|ComponentDescription=LED GREEN CLEAR SMD|PartCount=2|DisplayModeCount=1|IndexInSheet=92|OwnerPartId=-1|Location.X=880|Location.Y=800|Orientation=3|CurrentPartId=1|LibraryPath=*|SourceLibraryName=Altium Content Vault|TargetFileName=*|AreaColor=11599871|Color=128|PartIDLocked=T|DesignItemId=CMP-2000-05198-2|AllPinCount=2
|RECORD=2|OwnerIndex=1047|OwnerPartId=1|Electrical=4|PinConglomerate=49|PinLength=20|Location.X=880|Location.Y=780|Name=A|Designator=2|PinPropagationDelay=0.000000E+000
|RECORD=2|OwnerIndex=1047|OwnerPartId=1|Electrical=4|PinConglomerate=51|PinLength=20|Location.X=880|Location.Y=760|Name=C|Designator=1|PinPropagationDelay=0.000000E+000
|RECORD=13|OwnerIndex=1047|IsNotAccesible=T|IndexInSheet=2|OwnerPartId=1|Location.X=890|Location.Y=780|Corner.X=870|Corner.Y=780|LineWidth=1|Color=16711680
|RECORD=13|OwnerIndex=1047|IsNotAccesible=T|IndexInSheet=3|OwnerPartId=1|Location.X=890|Location.Y=760|Corner.X=870|Corner.Y=760|LineWidth=1|Color=16711680
|RECORD=13|OwnerIndex=1047|IsNotAccesible=T|IndexInSheet=4|OwnerPartId=1|Location.X=890|Location.Y=780|Corner.X=880|Corner.Y=760|LineWidth=1|Color=16711680
|RECORD=13|OwnerIndex=1047|IsNotAccesible=T|IndexInSheet=5|OwnerPartId=1|Location.X=870|Location.Y=780|Corner.X=880|Corner.Y=760|LineWidth=1|Color=16711680
|RECORD=13|OwnerIndex=1047|IsNotAccesible=T|IndexInSheet=6|OwnerPartId=1|Location.X=892|Location.Y=775|Corner.X=902|Corner.Y=765|LineWidth=1|Color=16711680
|RECORD=13|OwnerIndex=1047|IsNotAccesible=T|IndexInSheet=7|OwnerPartId=1|Location.X=902|Location.Y=765|Corner.X=902|Corner.Y=770|LineWidth=1|Color=16711680
|RECORD=13|OwnerIndex=1047|IsNotAccesible=T|IndexInSheet=8|OwnerPartId=1|Location.X=902|Location.Y=765|Corner.X=897|Corner.Y=765|LineWidth=1|Color=16711680
|RECORD=13|OwnerIndex=1047|IsNotAccesible=T|IndexInSheet=9|OwnerPartId=1|Location.X=888|Location.Y=768|Corner.X=898|Corner.Y=758|LineWidth=1|Color=16711680
|RECORD=13|OwnerIndex=1047|IsNotAccesible=T|IndexInSheet=10|OwnerPartId=1|Location.X=898|Location.Y=758|Corner.X=898|Corner.Y=763|LineWidth=1|Color=16711680
|RECORD=13|OwnerIndex=1047|IsNotAccesible=T|IndexInSheet=11|OwnerPartId=1|Location.X=898|Location.Y=758|Corner.X=893|Corner.Y=758|LineWidth=1|Color=16711680
|RECORD=13|OwnerIndex=1047|IsNotAccesible=T|IndexInSheet=12|OwnerPartId=1|Location.X=880|Location.Y=780|Corner.X=880|Corner.Y=783|LineWidth=1|Color=16711680
|RECORD=13|OwnerIndex=1047|IsNotAccesible=T|IndexInSheet=13|OwnerPartId=1|Location.X=880|Location.Y=760|Corner.X=880|Corner.Y=757|LineWidth=1|Color=16711680
|RECORD=41|OwnerIndex=1047|IndexInSheet=14|OwnerPartId=-1|Location.X=869|Location.Y=802|Color=8388608|FontID=1|IsHidden=T|Text=0.8mm|Name=Width
|RECORD=41|OwnerIndex=1047|IndexInSheet=15|OwnerPartId=-1|Location.X=869|Location.Y=802|Color=8388608|FontID=1|IsHidden=T|Text=0603|Name=Case Code (Imperial)
|RECORD=41|OwnerIndex=1047|IndexInSheet=16|OwnerPartId=-1|Location.X=869|Location.Y=802|Color=8388608|FontID=1|IsHidden=T|Text=2|Name=Number of Pins
|RECORD=41|OwnerIndex=1047|IndexInSheet=17|OwnerPartId=-1|Location.X=869|Location.Y=802|Color=8388608|FontID=1|IsHidden=T|Text=75mW|Name=Max Power Dissipation
|RECORD=41|OwnerIndex=1047|IndexInSheet=18|OwnerPartId=-1|Location.X=869|Location.Y=802|Color=8388608|FontID=1|IsHidden=T|Text=30mA|Name=Forward Current
|RECORD=41|OwnerIndex=1047|IndexInSheet=19|OwnerPartId=-1|Location.X=869|Location.Y=802|Color=8388608|FontID=1|IsHidden=T|Text=Lead Free|Name=Lead Free
|RECORD=41|OwnerIndex=1047|IndexInSheet=20|OwnerPartId=-1|Location.X=869|Location.Y=802|Color=8388608|FontID=1|IsHidden=T|Text=5V|Name=Reverse Voltage
|RECORD=41|OwnerIndex=1047|IndexInSheet=21|OwnerPartId=-1|Location.X=869|Location.Y=802|Color=8388608|FontID=1|IsHidden=T|Text=Colorless|Name=Lens Color
|RECORD=41|OwnerIndex=1047|IndexInSheet=22|OwnerPartId=-1|Location.X=869|Location.Y=802|Color=8388608|FontID=1|IsHidden=T|Text=2V|Name=Forward Voltage
|RECORD=41|OwnerIndex=1047|IndexInSheet=23|OwnerPartId=-1|Location.X=869|Location.Y=802|Color=8388608|FontID=1|IsHidden=T|Text=Tape and Reel|Name=Packaging
|RECORD=41|OwnerIndex=1047|IndexInSheet=24|OwnerPartId=-1|Location.X=869|Location.Y=802|Color=8388608|FontID=1|IsHidden=T|Text=1|Name=Package Quantity
|RECORD=41|OwnerIndex=1047|IndexInSheet=25|OwnerPartId=-1|Location.X=869|Location.Y=802|Color=8388608|FontID=1|IsHidden=T|Text=-55°C|Name=Min Operating Temperature
|RECORD=41|OwnerIndex=1047|IndexInSheet=26|OwnerPartId=-1|Location.X=869|Location.Y=802|Color=8388608|FontID=1|IsHidden=T|Text=0603|Name=Case/Package
|RECORD=41|OwnerIndex=1047|IndexInSheet=27|OwnerPartId=-1|Location.X=869|Location.Y=802|Color=8388608|FontID=1|IsHidden=T|Text=1.6mm|Name=Length
|RECORD=41|OwnerIndex=1047|IndexInSheet=28|OwnerPartId=-1|Location.X=869|Location.Y=802|Color=8388608|FontID=1|IsHidden=T|Text=75mW|Name=Power Dissipation
|RECORD=41|OwnerIndex=1047|IndexInSheet=29|OwnerPartId=-1|Location.X=869|Location.Y=802|Color=8388608|FontID=1|IsHidden=T|Text=571nm|Name=Dominant Wavelength
|RECORD=41|OwnerIndex=1047|IndexInSheet=30|OwnerPartId=-1|Location.X=869|Location.Y=802|Color=8388608|FontID=1|IsHidden=T|Text=0.8mm|Name=Depth
|RECORD=41|OwnerIndex=1047|IndexInSheet=31|OwnerPartId=-1|Location.X=869|Location.Y=802|Color=8388608|FontID=1|IsHidden=T|Text=No|Name=Radiation Hardening
|RECORD=41|OwnerIndex=1047|IndexInSheet=32|OwnerPartId=-1|Location.X=869|Location.Y=802|Color=8388608|FontID=1|IsHidden=T|Text=Surface Mount|Name=Mount
|RECORD=41|OwnerIndex=1047|IndexInSheet=33|OwnerPartId=-1|Location.X=869|Location.Y=802|Color=8388608|FontID=1|IsHidden=T|Text=85°C|Name=Max Operating Temperature
|RECORD=41|OwnerIndex=1047|IndexInSheet=34|OwnerPartId=-1|Location.X=869|Location.Y=802|Color=8388608|FontID=1|IsHidden=T|Text=Green|Name=Color
|RECORD=41|OwnerIndex=1047|IndexInSheet=35|OwnerPartId=-1|Location.X=869|Location.Y=802|Color=8388608|FontID=1|IsHidden=T|Text=75mW|Name=Power Rating
|RECORD=41|OwnerIndex=1047|IndexInSheet=36|OwnerPartId=-1|Location.X=869|Location.Y=802|Color=8388608|FontID=1|IsHidden=T|Text=0.55mm|Name=Height
|RECORD=41|OwnerIndex=1047|IndexInSheet=37|OwnerPartId=-1|Location.X=869|Location.Y=802|Color=8388608|FontID=1|IsHidden=T|Text=1|Name=Number of LEDs
|RECORD=41|OwnerIndex=1047|IndexInSheet=38|OwnerPartId=-1|Location.X=869|Location.Y=802|Color=8388608|FontID=1|IsHidden=T|Text=130°|Name=Viewing Angle
|RECORD=41|OwnerIndex=1047|IndexInSheet=39|OwnerPartId=-1|Location.X=869|Location.Y=802|Color=8388608|FontID=1|IsHidden=T|Text=Rectangular|Name=Lens Style
|RECORD=41|OwnerIndex=1047|IndexInSheet=40|OwnerPartId=-1|Location.X=869|Location.Y=802|Color=8388608|FontID=1|IsHidden=T|Text=Green|Name=Illumination Color
|RECORD=41|OwnerIndex=1047|IndexInSheet=41|OwnerPartId=-1|Location.X=869|Location.Y=802|Color=8388608|FontID=1|IsHidden=T|Text=20mA|Name=Test Current
|RECORD=41|OwnerIndex=1047|IndexInSheet=42|OwnerPartId=-1|Location.X=869|Location.Y=802|Color=8388608|FontID=1|IsHidden=T|Text=1608|Name=Case Code (Metric)
|RECORD=41|OwnerIndex=1047|IndexInSheet=43|OwnerPartId=-1|Location.X=869|Location.Y=802|Color=8388608|FontID=1|IsHidden=T|Text=Clear|Name=Lens Transparency
|RECORD=41|OwnerIndex=1047|IndexInSheet=44|OwnerPartId=-1|Location.X=869|Location.Y=802|Color=8388608|FontID=1|IsHidden=T|Text=35mcd|Name=Luminous Intensity
|RECORD=41|OwnerIndex=1047|IndexInSheet=45|OwnerPartId=-1|Location.X=869|Location.Y=802|Color=8388608|FontID=1|IsHidden=T|Text=1|Name=Number of Elements
|RECORD=41|OwnerIndex=1047|IndexInSheet=46|OwnerPartId=-1|Location.X=869|Location.Y=802|Color=8388608|FontID=1|IsHidden=T|Text=574nm|Name=Wavelength
|RECORD=34|OwnerIndex=1047|IndexInSheet=-1|OwnerPartId=-1|Location.X=865|Location.Y=760|Orientation=1|Color=8388608|FontID=2|Text=D11|Name=Designator|ReadOnlyState=1
|RECORD=41|OwnerIndex=1047|IndexInSheet=-1|OwnerPartId=1|Location.X=919|Location.Y=740|Orientation=1|Color=8388608|FontID=2|Text=LTST-C191KGKT|Name=Comment
|RECORD=44|OwnerIndex=1047
|RECORD=45|OwnerIndex=1099|IndexInSheet=-1|UseComponentLibrary=T|ModelName=FP-LTST-C191KGKT-MFG|ModelType=PCBLIB|DatafileCount=1|ModelDatafileEntity0=FP-LTST-C191KGKT-MFG|ModelDatafileKind0=PCBLib|IsCurrent=T|DatalinksLocked=T|DatabaseDatalinksLocked=T
|RECORD=46|OwnerIndex=1100
|RECORD=48|OwnerIndex=1100
|RECORD=27|IndexInSheet=93|OwnerPartId=-1|LineWidth=1|Color=8388608|LocationCount=2|X1=580|Y1=740|X2=580|Y2=730
|RECORD=27|IndexInSheet=94|OwnerPartId=-1|LineWidth=1|Color=8388608|LocationCount=2|X1=680|Y1=740|X2=680|Y2=730
|RECORD=27|IndexInSheet=95|OwnerPartId=-1|LineWidth=1|Color=8388608|LocationCount=2|X1=780|Y1=740|X2=780|Y2=730
|RECORD=27|IndexInSheet=96|OwnerPartId=-1|LineWidth=1|Color=8388608|LocationCount=2|X1=880|Y1=740|X2=880|Y2=730
|RECORD=27|IndexInSheet=97|OwnerPartId=-1|LineWidth=1|Color=8388608|LocationCount=3|X1=580|Y1=690|X2=580|Y2=669|X3=571|Y3=669
|RECORD=27|IndexInSheet=98|OwnerPartId=-1|LineWidth=1|Color=8388608|LocationCount=3|X1=680|Y1=690|X2=680|Y2=669|X3=671|Y3=669
|RECORD=27|IndexInSheet=99|OwnerPartId=-1|LineWidth=1|Color=8388608|LocationCount=3|X1=780|Y1=690|X2=780|Y2=669|X3=771|Y3=669
|RECORD=27|IndexInSheet=100|OwnerPartId=-1|LineWidth=1|Color=8388608|LocationCount=3|X1=880|Y1=690|X2=880|Y2=669|X3=871|Y3=669
|RECORD=27|IndexInSheet=101|OwnerPartId=-1|LineWidth=1|Color=8388608|LocationCount=4|X1=1114|Y1=505|X2=834|Y2=505|X3=834|Y3=445|X4=794|Y4=445
|RECORD=27|IndexInSheet=102|OwnerPartId=-1|LineWidth=1|Color=8388608|LocationCount=4|X1=794|Y1=435|X2=844|Y2=435|X3=844|Y3=495|X4=1114|Y4=495
|RECORD=27|IndexInSheet=103|OwnerPartId=-1|LineWidth=1|Color=8388608|LocationCount=4|X1=1114|Y1=485|X2=854|Y2=485|X3=854|Y3=425|X4=794|Y4=425
|RECORD=27|IndexInSheet=104|OwnerPartId=-1|LineWidth=1|Color=8388608|LocationCount=4|X1=794|Y1=405|X2=884|Y2=405|X3=884|Y3=445|X4=1114|Y4=445
|RECORD=27|IndexInSheet=105|OwnerPartId=-1|LineWidth=1|Color=8388608|LocationCount=4|X1=1114|Y1=435|X2=894|Y2=435|X3=894|Y3=395|X4=794|Y4=395
|RECORD=27|IndexInSheet=106|OwnerPartId=-1|LineWidth=1|Color=8388608|LocationCount=4|X1=794|Y1=385|X2=904|Y2=385|X3=904|Y3=425|X4=1114|Y4=425
|RECORD=27|IndexInSheet=107|OwnerPartId=-1|LineWidth=1|Color=8388608|LocationCount=4|X1=1114|Y1=385|X2=944|Y2=385|X3=944|Y3=365|X4=794|Y4=365
|RECORD=27|IndexInSheet=108|OwnerPartId=-1|LineWidth=1|Color=8388608|LocationCount=4|X1=794|Y1=355|X2=954|Y2=355|X3=954|Y3=375|X4=1114|Y4=375
|RECORD=27|IndexInSheet=109|OwnerPartId=-1|LineWidth=1|Color=8388608|LocationCount=4|X1=1114|Y1=365|X2=964|Y2=365|X3=964|Y3=345|X4=794|Y4=345
|RECORD=27|IndexInSheet=110|OwnerPartId=-1|LineWidth=1|Color=8388608|LocationCount=2|X1=794|Y1=325|X2=1114|Y2=325
|RECORD=27|IndexInSheet=111|OwnerPartId=-1|LineWidth=1|Color=8388608|LocationCount=2|X1=1114|Y1=315|X2=794|Y2=315
|RECORD=27|IndexInSheet=112|OwnerPartId=-1|LineWidth=1|Color=8388608|LocationCount=2|X1=794|Y1=305|X2=1114|Y2=305
|RECORD=27|IndexInSheet=113|OwnerPartId=-1|LineWidth=1|Color=8388608|LocationCount=4|X1=1114|Y1=255|X2=964|Y2=255|X3=964|Y3=285|X4=794|Y4=285
|RECORD=27|IndexInSheet=114|OwnerPartId=-1|LineWidth=1|Color=8388608|LocationCount=4|X1=794|Y1=275|X2=954|Y2=275|X3=954|Y3=245|X4=1114|Y4=245
|RECORD=27|IndexInSheet=115|OwnerPartId=-1|LineWidth=1|Color=8388608|LocationCount=4|X1=1114|Y1=235|X2=944|Y2=235|X3=944|Y3=265|X4=794|Y4=265
|RECORD=27|IndexInSheet=116|OwnerPartId=-1|LineWidth=1|Color=8388608|LocationCount=4|X1=794|Y1=245|X2=904|Y2=245|X3=904|Y3=185|X4=1114|Y4=185
|RECORD=27|IndexInSheet=117|OwnerPartId=-1|LineWidth=1|Color=8388608|LocationCount=4|X1=1114|Y1=175|X2=894|Y2=175|X3=894|Y3=235|X4=794|Y4=235
|RECORD=27|IndexInSheet=118|OwnerPartId=-1|LineWidth=1|Color=8388608|LocationCount=4|X1=794|Y1=225|X2=884|Y2=225|X3=884|Y3=165|X4=1114|Y4=165
|RECORD=27|IndexInSheet=119|OwnerPartId=-1|LineWidth=1|Color=8388608|LocationCount=2|X1=1214|Y1=255|X2=1244|Y2=255
|RECORD=27|IndexInSheet=120|OwnerPartId=-1|LineWidth=1|Color=8388608|LocationCount=2|X1=1214|Y1=325|X2=1244|Y2=325
|RECORD=27|IndexInSheet=121|OwnerPartId=-1|LineWidth=1|Color=8388608|LocationCount=2|X1=1214|Y1=385|X2=1244|Y2=385
|RECORD=27|IndexInSheet=122|OwnerPartId=-1|LineWidth=1|Color=8388608|LocationCount=2|X1=1214|Y1=445|X2=1244|Y2=445
|RECORD=27|IndexInSheet=123|OwnerPartId=-1|LineWidth=1|Color=8388608|LocationCount=2|X1=1214|Y1=505|X2=1244|Y2=505
|RECORD=27|IndexInSheet=124|OwnerPartId=-1|LineWidth=1|Color=8388608|LocationCount=2|X1=534|Y1=175|X2=534|Y2=155
|RECORD=27|IndexInSheet=125|OwnerPartId=-1|LineWidth=1|Color=8388608|LocationCount=2|X1=444|Y1=185|X2=444|Y2=155
|RECORD=27|IndexInSheet=126|OwnerPartId=-1|LineWidth=1|Color=8388608|LocationCount=3|X1=644|Y1=225|X2=614|Y2=225|X3=614|Y3=155
|RECORD=27|IndexInSheet=127|OwnerPartId=-1|LineWidth=1|Color=8388608|LocationCount=3|X1=644|Y1=235|X2=614|Y2=235|X3=614|Y3=225
|RECORD=27|IndexInSheet=128|OwnerPartId=-1|LineWidth=1|Color=8388608|LocationCount=3|X1=644|Y1=245|X2=614|Y2=245|X3=614|Y3=235
|RECORD=27|IndexInSheet=129|OwnerPartId=-1|LineWidth=1|Color=8388608|LocationCount=3|X1=644|Y1=255|X2=614|Y2=255|X3=614|Y3=245
|RECORD=27|IndexInSheet=130|OwnerPartId=-1|LineWidth=1|Color=8388608|LocationCount=3|X1=644|Y1=265|X2=614|Y2=265|X3=614|Y3=255
|RECORD=27|IndexInSheet=131|OwnerPartId=-1|LineWidth=1|Color=8388608|LocationCount=2|X1=364|Y1=165|X2=364|Y2=155
|RECORD=27|IndexInSheet=132|OwnerPartId=-1|LineWidth=1|Color=8388608|LocationCount=2|X1=464|Y1=295|X2=464|Y2=465
|RECORD=27|IndexInSheet=133|OwnerPartId=-1|LineWidth=1|Color=8388608|LocationCount=2|X1=644|Y1=445|X2=584|Y2=445
|RECORD=27|IndexInSheet=134|OwnerPartId=-1|LineWidth=1|Color=8388608|LocationCount=2|X1=644|Y1=435|X2=579|Y2=435
|RECORD=27|IndexInSheet=135|OwnerPartId=-1|LineWidth=1|Color=8388608|LocationCount=3|X1=644|Y1=365|X2=564|Y2=365|X3=564|Y3=215
|RECORD=27|IndexInSheet=136|OwnerPartId=-1|LineWidth=1|Color=8388608|LocationCount=2|X1=564|Y1=175|X2=564|Y2=155
|RECORD=27|IndexInSheet=137|OwnerPartId=-1|LineWidth=1|Color=8388608|LocationCount=2|X1=680|Y1=800|X2=680|Y2=830
|RECORD=27|IndexInSheet=138|OwnerPartId=-1|LineWidth=1|Color=8388608|LocationCount=2|X1=780|Y1=800|X2=780|Y2=830
|RECORD=27|IndexInSheet=139|OwnerPartId=-1|LineWidth=1|Color=8388608|LocationCount=2|X1=880|Y1=800|X2=880|Y2=830
|RECORD=27|IndexInSheet=140|OwnerPartId=-1|LineWidth=1|Color=8388608|LocationCount=2|X1=580|Y1=825|X2=580|Y2=800
|RECORD=27|IndexInSheet=141|OwnerPartId=-1|LineWidth=1|Color=8388608|LocationCount=2|X1=364|Y1=385|X2=364|Y2=395
|RECORD=27|IndexInSheet=142|OwnerPartId=-1|LineWidth=1|Color=8388608|LocationCount=2|X1=364|Y1=435|X2=364|Y2=455
|RECORD=27|IndexInSheet=143|OwnerPartId=-1|LineWidth=1|Color=8388608|LocationCount=2|X1=534|Y1=205|X2=534|Y2=295
|RECORD=27|IndexInSheet=144|OwnerPartId=-1|LineWidth=1|Color=8388608|LocationCount=2|X1=494|Y1=210|X2=494|Y2=150
|RECORD=27|IndexInSheet=145|OwnerPartId=-1|LineWidth=1|Color=8388608|LocationCount=2|X1=494|Y1=480|X2=494|Y2=490
|RECORD=27|IndexInSheet=146|OwnerPartId=-1|LineWidth=1|Color=8388608|LocationCount=2|X1=644|Y1=415|X2=494|Y2=415
|RECORD=27|IndexInSheet=147|OwnerPartId=-1|LineWidth=1|Color=8388608|LocationCount=3|X1=364|Y1=235|X2=364|Y2=385|X3=644|Y3=385
|RECORD=27|IndexInSheet=148|OwnerPartId=-1|LineWidth=1|Color=8388608|LocationCount=5|X1=644|Y1=295|X2=534|Y2=295|X3=464|Y3=295|X4=444|Y4=295|X5=444|Y5=205
|RECORD=27|IndexInSheet=149|OwnerPartId=-1|LineWidth=1|Color=8388608|LocationCount=8|X1=1244|Y1=555|X2=1244|Y2=505|X3=1244|Y3=445|X4=1244|Y4=385|X5=1244|Y5=325|X6=1244|Y6=255|X7=1244|Y7=185|X8=1214|Y8=185
|RECORD=27|IndexInSheet=150|OwnerPartId=-1|LineWidth=1|Color=8388608|LocationCount=3|X1=494|Y1=250|X2=494|Y2=415|X3=494|Y3=440
|RECORD=29|IndexInSheet=-1|OwnerPartId=-1|Location.X=364|Location.Y=385|Color=128
|RECORD=29|IndexInSheet=-1|OwnerPartId=-1|Location.X=464|Location.Y=295|Color=128
|RECORD=29|IndexInSheet=-1|OwnerPartId=-1|Location.X=494|Location.Y=415|Color=128
|RECORD=29|IndexInSheet=-1|OwnerPartId=-1|Location.X=534|Location.Y=295|Color=128
|RECORD=29|IndexInSheet=-1|OwnerPartId=-1|Location.X=614|Location.Y=225|Color=128
|RECORD=29|IndexInSheet=-1|OwnerPartId=-1|Location.X=614|Location.Y=235|Color=128
|RECORD=29|IndexInSheet=-1|OwnerPartId=-1|Location.X=614|Location.Y=245|Color=128
|RECORD=29|IndexInSheet=-1|OwnerPartId=-1|Location.X=614|Location.Y=255|Color=128
|RECORD=29|IndexInSheet=-1|OwnerPartId=-1|Location.X=1244|Location.Y=255|Color=128
|RECORD=29|IndexInSheet=-1|OwnerPartId=-1|Location.X=1244|Location.Y=325|Color=128
|RECORD=29|IndexInSheet=-1|OwnerPartId=-1|Location.X=1244|Location.Y=385|Color=128
|RECORD=29|IndexInSheet=-1|OwnerPartId=-1|Location.X=1244|Location.Y=445|Color=128
|RECORD=29|IndexInSheet=-1|OwnerPartId=-1|Location.X=1244|Location.Y=505|Color=128